FILE_TYPE = MACRO_DRAWING;
SET COLOR_WIRE YELLOW;
SET COLOR_PROP ORANGE;
SET COLOR_DOT WHITE;
SET COLOR_ARC YELLOW;
SET COLOR_BODY GREEN;
SET COLOR_NOTE PURPLE;
SET PROP_DISPLAY VALUE;
SET PAGE_NUMBER P30;
FORCEADD GENOA_SP5..27
(-2475 3550);
FORCEPROP 1 LAST LOCATION U25
J 0
(-2975 6700);
DISPLAY 0.489362 (-2975 6700);
PAINT SKYBLUE (-2975 6700);
FORCEPROP 0 LAST $SEC 27
J 0
(-2950 6975);
DISPLAY 0.680851 (-2950 6975);
PAINT MONO (-2950 6975);
DISPLAY INVISIBLE (-2950 6975);
FORCEPROP 0 LAST CDS_SEC 27
J 0
(-1700 6650);
DISPLAY 1.021277 (-1700 6650);
DISPLAY INVISIBLE (-1700 6650);
FORCEPROP 0 LASTPIN (-3125 6525) $PN BJ18
J 2
(-3135 6535);
DISPLAY 0.489362 (-3135 6535);
PAINT MONO (-3135 6535);
FORCEPROP 0 LASTPIN (-3125 6475) $PN BJ23
J 2
(-3135 6485);
DISPLAY 0.489362 (-3135 6485);
PAINT MONO (-3135 6485);
FORCEPROP 0 LASTPIN (-3125 6425) $PN BJ25
J 2
(-3135 6435);
DISPLAY 0.489362 (-3135 6435);
PAINT MONO (-3135 6435);
FORCEPROP 0 LASTPIN (-3125 6375) $PN BJ27
J 2
(-3135 6385);
DISPLAY 0.489362 (-3135 6385);
PAINT MONO (-3135 6385);
FORCEPROP 0 LASTPIN (-3125 6325) $PN BK22
J 2
(-3135 6335);
DISPLAY 0.489362 (-3135 6335);
PAINT MONO (-3135 6335);
FORCEPROP 0 LASTPIN (-3125 6275) $PN BK24
J 2
(-3135 6285);
DISPLAY 0.489362 (-3135 6285);
PAINT MONO (-3135 6285);
FORCEPROP 0 LASTPIN (-3125 6225) $PN BK26
J 2
(-3135 6235);
DISPLAY 0.489362 (-3135 6235);
PAINT MONO (-3135 6235);
FORCEPROP 0 LASTPIN (-3125 6175) $PN BK28
J 2
(-3135 6185);
DISPLAY 0.489362 (-3135 6185);
PAINT MONO (-3135 6185);
FORCEPROP 0 LASTPIN (-3125 6125) $PN BK49
J 2
(-3135 6135);
DISPLAY 0.489362 (-3135 6135);
PAINT MONO (-3135 6135);
FORCEPROP 0 LASTPIN (-3125 6075) $PN BL23
J 2
(-3135 6085);
DISPLAY 0.489362 (-3135 6085);
PAINT MONO (-3135 6085);
FORCEPROP 0 LASTPIN (-3125 6025) $PN BL25
J 2
(-3135 6035);
DISPLAY 0.489362 (-3135 6035);
PAINT MONO (-3135 6035);
FORCEPROP 0 LASTPIN (-3125 5975) $PN BL27
J 2
(-3135 5985);
DISPLAY 0.489362 (-3135 5985);
PAINT MONO (-3135 5985);
FORCEPROP 0 LASTPIN (-3125 5925) $PN BL48
J 2
(-3135 5935);
DISPLAY 0.489362 (-3135 5935);
PAINT MONO (-3135 5935);
FORCEPROP 0 LASTPIN (-3125 5875) $PN BM12
J 2
(-3135 5885);
DISPLAY 0.489362 (-3135 5885);
PAINT MONO (-3135 5885);
FORCEPROP 0 LASTPIN (-3125 5825) $PN BM19
J 2
(-3135 5835);
DISPLAY 0.489362 (-3135 5835);
PAINT MONO (-3135 5835);
FORCEPROP 0 LASTPIN (-3125 5775) $PN BM22
J 2
(-3135 5785);
DISPLAY 0.489362 (-3135 5785);
PAINT MONO (-3135 5785);
FORCEPROP 0 LASTPIN (-3125 5725) $PN BM24
J 2
(-3135 5735);
DISPLAY 0.489362 (-3135 5735);
PAINT MONO (-3135 5735);
FORCEPROP 0 LASTPIN (-3125 5675) $PN BM26
J 2
(-3135 5685);
DISPLAY 0.489362 (-3135 5685);
PAINT MONO (-3135 5685);
FORCEPROP 0 LASTPIN (-3125 5625) $PN BM28
J 2
(-3135 5635);
DISPLAY 0.489362 (-3135 5635);
PAINT MONO (-3135 5635);
FORCEPROP 0 LASTPIN (-3125 5575) $PN BM30
J 2
(-3135 5585);
DISPLAY 0.489362 (-3135 5585);
PAINT MONO (-3135 5585);
FORCEPROP 0 LASTPIN (-3125 5525) $PN BM32
J 2
(-3135 5535);
DISPLAY 0.489362 (-3135 5535);
PAINT MONO (-3135 5535);
FORCEPROP 0 LASTPIN (-3125 5475) $PN BM34
J 2
(-3135 5485);
DISPLAY 0.489362 (-3135 5485);
PAINT MONO (-3135 5485);
FORCEPROP 0 LASTPIN (-3125 5425) $PN BM36
J 2
(-3135 5435);
DISPLAY 0.489362 (-3135 5435);
PAINT MONO (-3135 5435);
FORCEPROP 0 LASTPIN (-3125 5375) $PN BM39
J 2
(-3135 5385);
DISPLAY 0.489362 (-3135 5385);
PAINT MONO (-3135 5385);
FORCEPROP 0 LASTPIN (-3125 5325) $PN BM41
J 2
(-3135 5335);
DISPLAY 0.489362 (-3135 5335);
PAINT MONO (-3135 5335);
FORCEPROP 0 LASTPIN (-3125 5275) $PN BM43
J 2
(-3135 5285);
DISPLAY 0.489362 (-3135 5285);
PAINT MONO (-3135 5285);
FORCEPROP 0 LASTPIN (-3125 5225) $PN BM45
J 2
(-3135 5235);
DISPLAY 0.489362 (-3135 5235);
PAINT MONO (-3135 5235);
FORCEPROP 0 LASTPIN (-3125 5175) $PN BM47
J 2
(-3135 5185);
DISPLAY 0.489362 (-3135 5185);
PAINT MONO (-3135 5185);
FORCEPROP 0 LASTPIN (-3125 5125) $PN BM49
J 2
(-3135 5135);
DISPLAY 0.489362 (-3135 5135);
PAINT MONO (-3135 5135);
FORCEPROP 0 LASTPIN (-3125 5075) $PN BN25
J 2
(-3135 5085);
DISPLAY 0.489362 (-3135 5085);
PAINT MONO (-3135 5085);
FORCEPROP 0 LASTPIN (-3125 5025) $PN BN29
J 2
(-3135 5035);
DISPLAY 0.489362 (-3135 5035);
PAINT MONO (-3135 5035);
FORCEPROP 0 LASTPIN (-3125 4975) $PN BN33
J 2
(-3135 4985);
DISPLAY 0.489362 (-3135 4985);
PAINT MONO (-3135 4985);
FORCEPROP 0 LASTPIN (-3125 4925) $PN BN40
J 2
(-3135 4935);
DISPLAY 0.489362 (-3135 4935);
PAINT MONO (-3135 4935);
FORCEPROP 0 LASTPIN (-3125 4875) $PN BN44
J 2
(-3135 4885);
DISPLAY 0.489362 (-3135 4885);
PAINT MONO (-3135 4885);
FORCEPROP 0 LASTPIN (-3125 4825) $PN BN48
J 2
(-3135 4835);
DISPLAY 0.489362 (-3135 4835);
PAINT MONO (-3135 4835);
FORCEPROP 0 LASTPIN (-3125 4775) $PN BP22
J 2
(-3135 4785);
DISPLAY 0.489362 (-3135 4785);
PAINT MONO (-3135 4785);
FORCEPROP 0 LASTPIN (-3125 4725) $PN BR4
J 2
(-3135 4735);
DISPLAY 0.489362 (-3135 4735);
PAINT MONO (-3135 4735);
FORCEPROP 0 LASTPIN (-3125 4675) $PN BR11
J 2
(-3135 4685);
DISPLAY 0.489362 (-3135 4685);
PAINT MONO (-3135 4685);
FORCEPROP 0 LASTPIN (-3125 4625) $PN BR18
J 2
(-3135 4635);
DISPLAY 0.489362 (-3135 4635);
PAINT MONO (-3135 4635);
FORCEPROP 0 LASTPIN (-3125 4575) $PN BV5
J 2
(-3135 4585);
DISPLAY 0.489362 (-3135 4585);
PAINT MONO (-3135 4585);
FORCEPROP 0 LASTPIN (-3125 4525) $PN BV12
J 2
(-3135 4535);
DISPLAY 0.489362 (-3135 4535);
PAINT MONO (-3135 4535);
FORCEPROP 0 LASTPIN (-3125 4475) $PN BV19
J 2
(-3135 4485);
DISPLAY 0.489362 (-3135 4485);
PAINT MONO (-3135 4485);
FORCEPROP 0 LASTPIN (-3125 4425) $PN BV22
J 2
(-3135 4435);
DISPLAY 0.489362 (-3135 4435);
PAINT MONO (-3135 4435);
FORCEPROP 0 LASTPIN (-3125 4375) $PN CA4
J 2
(-3135 4385);
DISPLAY 0.489362 (-3135 4385);
PAINT MONO (-3135 4385);
FORCEPROP 0 LASTPIN (-3125 4325) $PN CA11
J 2
(-3135 4335);
DISPLAY 0.489362 (-3135 4335);
PAINT MONO (-3135 4335);
FORCEPROP 0 LASTPIN (-3125 4275) $PN CA18
J 2
(-3135 4285);
DISPLAY 0.489362 (-3135 4285);
PAINT MONO (-3135 4285);
FORCEPROP 0 LASTPIN (-3125 4225) $PN CB22
J 2
(-3135 4235);
DISPLAY 0.489362 (-3135 4235);
PAINT MONO (-3135 4235);
FORCEPROP 0 LASTPIN (-3125 4175) $PN CD5
J 2
(-3135 4185);
DISPLAY 0.489362 (-3135 4185);
PAINT MONO (-3135 4185);
FORCEPROP 0 LASTPIN (-3125 4125) $PN CD12
J 2
(-3135 4135);
DISPLAY 0.489362 (-3135 4135);
PAINT MONO (-3135 4135);
FORCEPROP 0 LASTPIN (-3125 4075) $PN CD19
J 2
(-3135 4085);
DISPLAY 0.489362 (-3135 4085);
PAINT MONO (-3135 4085);
FORCEPROP 0 LASTPIN (-3125 4025) $PN CF22
J 2
(-3135 4035);
DISPLAY 0.489362 (-3135 4035);
PAINT MONO (-3135 4035);
FORCEPROP 0 LASTPIN (-3125 3975) $PN CG4
J 2
(-3135 3985);
DISPLAY 0.489362 (-3135 3985);
PAINT MONO (-3135 3985);
FORCEPROP 0 LASTPIN (-3125 3925) $PN CG11
J 2
(-3135 3935);
DISPLAY 0.489362 (-3135 3935);
PAINT MONO (-3135 3935);
FORCEPROP 0 LASTPIN (-3125 3875) $PN CG18
J 2
(-3135 3885);
DISPLAY 0.489362 (-3135 3885);
PAINT MONO (-3135 3885);
FORCEPROP 0 LASTPIN (-3125 3825) $PN CJ22
J 2
(-3135 3835);
DISPLAY 0.489362 (-3135 3835);
PAINT MONO (-3135 3835);
FORCEPROP 0 LASTPIN (-3125 3775) $PN CK5
J 2
(-3135 3785);
DISPLAY 0.489362 (-3135 3785);
PAINT MONO (-3135 3785);
FORCEPROP 0 LASTPIN (-3125 3725) $PN CK12
J 2
(-3135 3735);
DISPLAY 0.489362 (-3135 3735);
PAINT MONO (-3135 3735);
FORCEPROP 0 LASTPIN (-3125 3675) $PN CK19
J 2
(-3135 3685);
DISPLAY 0.489362 (-3135 3685);
PAINT MONO (-3135 3685);
FORCEPROP 0 LASTPIN (-3125 3625) $PN CM22
J 2
(-3135 3635);
DISPLAY 0.489362 (-3135 3635);
PAINT MONO (-3135 3635);
FORCEPROP 0 LASTPIN (-3125 3575) $PN CN4
J 2
(-3135 3585);
DISPLAY 0.489362 (-3135 3585);
PAINT MONO (-3135 3585);
FORCEPROP 0 LASTPIN (-3125 3525) $PN CN11
J 2
(-3135 3535);
DISPLAY 0.489362 (-3135 3535);
PAINT MONO (-3135 3535);
FORCEPROP 0 LASTPIN (-3125 3475) $PN CN18
J 2
(-3135 3485);
DISPLAY 0.489362 (-3135 3485);
PAINT MONO (-3135 3485);
FORCEPROP 0 LASTPIN (-3125 3425) $PN CT5
J 2
(-3135 3435);
DISPLAY 0.489362 (-3135 3435);
PAINT MONO (-3135 3435);
FORCEPROP 0 LASTPIN (-3125 3375) $PN CT12
J 2
(-3135 3385);
DISPLAY 0.489362 (-3135 3385);
PAINT MONO (-3135 3385);
FORCEPROP 0 LASTPIN (-3125 3325) $PN CT19
J 2
(-3135 3335);
DISPLAY 0.489362 (-3135 3335);
PAINT MONO (-3135 3335);
FORCEPROP 0 LASTPIN (-3125 3275) $PN CT22
J 2
(-3135 3285);
DISPLAY 0.489362 (-3135 3285);
PAINT MONO (-3135 3285);
FORCEPROP 0 LASTPIN (-3125 3225) $PN CW4
J 2
(-3135 3235);
DISPLAY 0.489362 (-3135 3235);
PAINT MONO (-3135 3235);
FORCEPROP 0 LASTPIN (-3125 3175) $PN CW11
J 2
(-3135 3185);
DISPLAY 0.489362 (-3135 3185);
PAINT MONO (-3135 3185);
FORCEPROP 0 LASTPIN (-3125 3125) $PN CW18
J 2
(-3135 3135);
DISPLAY 0.489362 (-3135 3135);
PAINT MONO (-3135 3135);
FORCEPROP 0 LASTPIN (-3125 3075) $PN CY22
J 2
(-3135 3085);
DISPLAY 0.489362 (-3135 3085);
PAINT MONO (-3135 3085);
FORCEPROP 0 LASTPIN (-3125 3025) $PN DB5
J 2
(-3135 3035);
DISPLAY 0.489362 (-3135 3035);
PAINT MONO (-3135 3035);
FORCEPROP 0 LASTPIN (-3125 2975) $PN DB12
J 2
(-3135 2985);
DISPLAY 0.489362 (-3135 2985);
PAINT MONO (-3135 2985);
FORCEPROP 0 LASTPIN (-3125 2925) $PN DB19
J 2
(-3135 2935);
DISPLAY 0.489362 (-3135 2935);
PAINT MONO (-3135 2935);
FORCEPROP 0 LASTPIN (-3125 2875) $PN DE4
J 2
(-3135 2885);
DISPLAY 0.489362 (-3135 2885);
PAINT MONO (-3135 2885);
FORCEPROP 0 LASTPIN (-3125 2825) $PN DE11
J 2
(-3135 2835);
DISPLAY 0.489362 (-3135 2835);
PAINT MONO (-3135 2835);
FORCEPROP 0 LASTPIN (-3125 2775) $PN DE18
J 2
(-3135 2785);
DISPLAY 0.489362 (-3135 2785);
PAINT MONO (-3135 2785);
FORCEPROP 0 LASTPIN (-3125 2725) $PN DG5
J 2
(-3135 2735);
DISPLAY 0.489362 (-3135 2735);
PAINT MONO (-3135 2735);
FORCEPROP 0 LASTPIN (-3125 2525) $PN AR52
J 2
(-3135 2535);
DISPLAY 0.489362 (-3135 2535);
PAINT MONO (-3135 2535);
FORCEPROP 0 LASTPIN (-3125 2475) $PN AR54
J 2
(-3135 2485);
DISPLAY 0.489362 (-3135 2485);
PAINT MONO (-3135 2485);
FORCEPROP 0 LASTPIN (-3125 2425) $PN AT51
J 2
(-3135 2435);
DISPLAY 0.489362 (-3135 2435);
PAINT MONO (-3135 2435);
FORCEPROP 0 LASTPIN (-3125 2375) $PN AT53
J 2
(-3135 2385);
DISPLAY 0.489362 (-3135 2385);
PAINT MONO (-3135 2385);
FORCEPROP 0 LASTPIN (-3125 2325) $PN AU50
J 2
(-3135 2335);
DISPLAY 0.489362 (-3135 2335);
PAINT MONO (-3135 2335);
FORCEPROP 0 LASTPIN (-3125 2275) $PN AU52
J 2
(-3135 2285);
DISPLAY 0.489362 (-3135 2285);
PAINT MONO (-3135 2285);
FORCEPROP 0 LASTPIN (-3125 1175) $PN AU54
J 2
(-3135 1185);
DISPLAY 0.489362 (-3135 1185);
PAINT MONO (-3135 1185);
FORCEPROP 0 LASTPIN (-3125 2225) $PN AV49
J 2
(-3135 2235);
DISPLAY 0.489362 (-3135 2235);
PAINT MONO (-3135 2235);
FORCEPROP 0 LASTPIN (-3125 2175) $PN AV51
J 2
(-3135 2185);
DISPLAY 0.489362 (-3135 2185);
PAINT MONO (-3135 2185);
FORCEPROP 0 LASTPIN (-3125 2125) $PN AV53
J 2
(-3135 2135);
DISPLAY 0.489362 (-3135 2135);
PAINT MONO (-3135 2135);
FORCEPROP 0 LASTPIN (-3125 2075) $PN AW50
J 2
(-3135 2085);
DISPLAY 0.489362 (-3135 2085);
PAINT MONO (-3135 2085);
FORCEPROP 0 LASTPIN (-3125 2025) $PN AW52
J 2
(-3135 2035);
DISPLAY 0.489362 (-3135 2035);
PAINT MONO (-3135 2035);
FORCEPROP 0 LASTPIN (-3125 1975) $PN AW54
J 2
(-3135 1985);
DISPLAY 0.489362 (-3135 1985);
PAINT MONO (-3135 1985);
FORCEPROP 0 LASTPIN (-3125 1925) $PN AY51
J 2
(-3135 1935);
DISPLAY 0.489362 (-3135 1935);
PAINT MONO (-3135 1935);
FORCEPROP 0 LASTPIN (-3125 1875) $PN AY53
J 2
(-3135 1885);
DISPLAY 0.489362 (-3135 1885);
PAINT MONO (-3135 1885);
FORCEPROP 0 LASTPIN (-3125 1825) $PN BA50
J 2
(-3135 1835);
DISPLAY 0.489362 (-3135 1835);
PAINT MONO (-3135 1835);
FORCEPROP 0 LASTPIN (-3125 1775) $PN BA52
J 2
(-3135 1785);
DISPLAY 0.489362 (-3135 1785);
PAINT MONO (-3135 1785);
FORCEPROP 0 LASTPIN (-3125 1725) $PN BA54
J 2
(-3135 1735);
DISPLAY 0.489362 (-3135 1735);
PAINT MONO (-3135 1735);
FORCEPROP 0 LASTPIN (-3125 1675) $PN BB51
J 2
(-3135 1685);
DISPLAY 0.489362 (-3135 1685);
PAINT MONO (-3135 1685);
FORCEPROP 0 LASTPIN (-3125 1625) $PN BB53
J 2
(-3135 1635);
DISPLAY 0.489362 (-3135 1635);
PAINT MONO (-3135 1635);
FORCEPROP 0 LASTPIN (-3125 1575) $PN BC52
J 2
(-3135 1585);
DISPLAY 0.489362 (-3135 1585);
PAINT MONO (-3135 1585);
FORCEPROP 0 LASTPIN (-3125 1525) $PN BC54
J 2
(-3135 1535);
DISPLAY 0.489362 (-3135 1535);
PAINT MONO (-3135 1535);
FORCEPROP 0 LASTPIN (-3125 925) $PN BN52
J 2
(-3135 935);
DISPLAY 0.489362 (-3135 935);
PAINT MONO (-3135 935);
FORCEPROP 0 LASTPIN (-3125 875) $PN BP51
J 2
(-3135 885);
DISPLAY 0.489362 (-3135 885);
PAINT MONO (-3135 885);
FORCEPROP 0 LASTPIN (-1825 625) $PN BN23
J 0
(-1815 635);
DISPLAY 0.489362 (-1815 635);
PAINT MONO (-1815 635);
FORCEPROP 0 LASTPIN (-1825 5625) $PN AA54
J 0
(-1815 5635);
DISPLAY 0.489362 (-1815 5635);
PAINT MONO (-1815 5635);
FORCEPROP 0 LASTPIN (-1825 5575) $PN AC58
J 0
(-1815 5585);
DISPLAY 0.489362 (-1815 5585);
PAINT MONO (-1815 5585);
FORCEPROP 0 LASTPIN (-1825 5525) $PN AC65
J 0
(-1815 5535);
DISPLAY 0.489362 (-1815 5535);
PAINT MONO (-1815 5535);
FORCEPROP 0 LASTPIN (-1825 5475) $PN AC72
J 0
(-1815 5485);
DISPLAY 0.489362 (-1815 5485);
PAINT MONO (-1815 5485);
FORCEPROP 0 LASTPIN (-1825 5425) $PN AD54
J 0
(-1815 5435);
DISPLAY 0.489362 (-1815 5435);
PAINT MONO (-1815 5435);
FORCEPROP 0 LASTPIN (-1825 5375) $PN AF57
J 0
(-1815 5385);
DISPLAY 0.489362 (-1815 5385);
PAINT MONO (-1815 5385);
FORCEPROP 0 LASTPIN (-1825 5325) $PN AF64
J 0
(-1815 5335);
DISPLAY 0.489362 (-1815 5335);
PAINT MONO (-1815 5335);
FORCEPROP 0 LASTPIN (-1825 5275) $PN AF71
J 0
(-1815 5285);
DISPLAY 0.489362 (-1815 5285);
PAINT MONO (-1815 5285);
FORCEPROP 0 LASTPIN (-1825 5225) $PN AH54
J 0
(-1815 5235);
DISPLAY 0.489362 (-1815 5235);
PAINT MONO (-1815 5235);
FORCEPROP 0 LASTPIN (-1825 5175) $PN AJ58
J 0
(-1815 5185);
DISPLAY 0.489362 (-1815 5185);
PAINT MONO (-1815 5185);
FORCEPROP 0 LASTPIN (-1825 5125) $PN AJ65
J 0
(-1815 5135);
DISPLAY 0.489362 (-1815 5135);
PAINT MONO (-1815 5135);
FORCEPROP 0 LASTPIN (-1825 5075) $PN AJ72
J 0
(-1815 5085);
DISPLAY 0.489362 (-1815 5085);
PAINT MONO (-1815 5085);
FORCEPROP 0 LASTPIN (-1825 5025) $PN AM54
J 0
(-1815 5035);
DISPLAY 0.489362 (-1815 5035);
PAINT MONO (-1815 5035);
FORCEPROP 0 LASTPIN (-1825 4975) $PN AM57
J 0
(-1815 4985);
DISPLAY 0.489362 (-1815 4985);
PAINT MONO (-1815 4985);
FORCEPROP 0 LASTPIN (-1825 4925) $PN AM64
J 0
(-1815 4935);
DISPLAY 0.489362 (-1815 4935);
PAINT MONO (-1815 4935);
FORCEPROP 0 LASTPIN (-1825 4875) $PN AM71
J 0
(-1815 4885);
DISPLAY 0.489362 (-1815 4885);
PAINT MONO (-1815 4885);
FORCEPROP 0 LASTPIN (-1825 4825) $PN AR58
J 0
(-1815 4835);
DISPLAY 0.489362 (-1815 4835);
PAINT MONO (-1815 4835);
FORCEPROP 0 LASTPIN (-1825 4775) $PN AR65
J 0
(-1815 4785);
DISPLAY 0.489362 (-1815 4785);
PAINT MONO (-1815 4785);
FORCEPROP 0 LASTPIN (-1825 4725) $PN AR72
J 0
(-1815 4735);
DISPLAY 0.489362 (-1815 4735);
PAINT MONO (-1815 4735);
FORCEPROP 0 LASTPIN (-3125 2625) $PN BH27
J 2
(-3135 2635);
DISPLAY 0.489362 (-3135 2635);
PAINT MONO (-3135 2635);
FORCEPROP 0 LASTPIN (-1825 4675) $PN AV57
J 0
(-1815 4685);
DISPLAY 0.489362 (-1815 4685);
PAINT MONO (-1815 4685);
FORCEPROP 0 LASTPIN (-1825 4625) $PN AV64
J 0
(-1815 4635);
DISPLAY 0.489362 (-1815 4635);
PAINT MONO (-1815 4635);
FORCEPROP 0 LASTPIN (-1825 4575) $PN AV71
J 0
(-1815 4585);
DISPLAY 0.489362 (-1815 4585);
PAINT MONO (-1815 4585);
FORCEPROP 0 LASTPIN (-1825 4525) $PN BA58
J 0
(-1815 4535);
DISPLAY 0.489362 (-1815 4535);
PAINT MONO (-1815 4535);
FORCEPROP 0 LASTPIN (-1825 4475) $PN BA65
J 0
(-1815 4485);
DISPLAY 0.489362 (-1815 4485);
PAINT MONO (-1815 4485);
FORCEPROP 0 LASTPIN (-1825 4425) $PN BA72
J 0
(-1815 4435);
DISPLAY 0.489362 (-1815 4435);
PAINT MONO (-1815 4435);
FORCEPROP 0 LASTPIN (-1825 4375) $PN BD50
J 0
(-1815 4385);
DISPLAY 0.489362 (-1815 4385);
PAINT MONO (-1815 4385);
FORCEPROP 0 LASTPIN (-1825 4325) $PN BD52
J 0
(-1815 4335);
DISPLAY 0.489362 (-1815 4335);
PAINT MONO (-1815 4335);
FORCEPROP 0 LASTPIN (-1825 4275) $PN BD54
J 0
(-1815 4285);
DISPLAY 0.489362 (-1815 4285);
PAINT MONO (-1815 4285);
FORCEPROP 0 LASTPIN (-1825 4225) $PN BF51
J 0
(-1815 4235);
DISPLAY 0.489362 (-1815 4235);
PAINT MONO (-1815 4235);
FORCEPROP 0 LASTPIN (-1825 4175) $PN BF53
J 0
(-1815 4185);
DISPLAY 0.489362 (-1815 4185);
PAINT MONO (-1815 4185);
FORCEPROP 0 LASTPIN (-1825 4125) $PN BF57
J 0
(-1815 4135);
DISPLAY 0.489362 (-1815 4135);
PAINT MONO (-1815 4135);
FORCEPROP 0 LASTPIN (-1825 4075) $PN BF64
J 0
(-1815 4085);
DISPLAY 0.489362 (-1815 4085);
PAINT MONO (-1815 4085);
FORCEPROP 0 LASTPIN (-1825 4025) $PN BF71
J 0
(-1815 4035);
DISPLAY 0.489362 (-1815 4035);
PAINT MONO (-1815 4035);
FORCEPROP 0 LASTPIN (-1825 3975) $PN BG50
J 0
(-1815 3985);
DISPLAY 0.489362 (-1815 3985);
PAINT MONO (-1815 3985);
FORCEPROP 0 LASTPIN (-1825 3925) $PN BG52
J 0
(-1815 3935);
DISPLAY 0.489362 (-1815 3935);
PAINT MONO (-1815 3935);
FORCEPROP 0 LASTPIN (-1825 3875) $PN BG54
J 0
(-1815 3885);
DISPLAY 0.489362 (-1815 3885);
PAINT MONO (-1815 3885);
FORCEPROP 0 LASTPIN (-1825 3825) $PN BH51
J 0
(-1815 3835);
DISPLAY 0.489362 (-1815 3835);
PAINT MONO (-1815 3835);
FORCEPROP 0 LASTPIN (-1825 3775) $PN BH53
J 0
(-1815 3785);
DISPLAY 0.489362 (-1815 3785);
PAINT MONO (-1815 3785);
FORCEPROP 0 LASTPIN (-1825 3725) $PN BJ50
J 0
(-1815 3735);
DISPLAY 0.489362 (-1815 3735);
PAINT MONO (-1815 3735);
FORCEPROP 0 LASTPIN (-1825 3675) $PN BJ52
J 0
(-1815 3685);
DISPLAY 0.489362 (-1815 3685);
PAINT MONO (-1815 3685);
FORCEPROP 0 LASTPIN (-1825 3625) $PN BJ54
J 0
(-1815 3635);
DISPLAY 0.489362 (-1815 3635);
PAINT MONO (-1815 3635);
FORCEPROP 0 LASTPIN (-1825 3575) $PN BJ58
J 0
(-1815 3585);
DISPLAY 0.489362 (-1815 3585);
PAINT MONO (-1815 3585);
FORCEPROP 0 LASTPIN (-1825 3525) $PN BJ65
J 0
(-1815 3535);
DISPLAY 0.489362 (-1815 3535);
PAINT MONO (-1815 3535);
FORCEPROP 0 LASTPIN (-1825 3475) $PN BJ72
J 0
(-1815 3485);
DISPLAY 0.489362 (-1815 3485);
PAINT MONO (-1815 3485);
FORCEPROP 0 LASTPIN (-1825 3425) $PN BK51
J 0
(-1815 3435);
DISPLAY 0.489362 (-1815 3435);
PAINT MONO (-1815 3435);
FORCEPROP 0 LASTPIN (-1825 3375) $PN BK53
J 0
(-1815 3385);
DISPLAY 0.489362 (-1815 3385);
PAINT MONO (-1815 3385);
FORCEPROP 0 LASTPIN (-1825 3325) $PN BL50
J 0
(-1815 3335);
DISPLAY 0.489362 (-1815 3335);
PAINT MONO (-1815 3335);
FORCEPROP 0 LASTPIN (-1825 3275) $PN BL52
J 0
(-1815 3285);
DISPLAY 0.489362 (-1815 3285);
PAINT MONO (-1815 3285);
FORCEPROP 0 LASTPIN (-1825 3225) $PN BL54
J 0
(-1815 3235);
DISPLAY 0.489362 (-1815 3235);
PAINT MONO (-1815 3235);
FORCEPROP 0 LASTPIN (-1825 3175) $PN BM51
J 0
(-1815 3185);
DISPLAY 0.489362 (-1815 3185);
PAINT MONO (-1815 3185);
FORCEPROP 0 LASTPIN (-1825 3125) $PN BM53
J 0
(-1815 3135);
DISPLAY 0.489362 (-1815 3135);
PAINT MONO (-1815 3135);
FORCEPROP 0 LASTPIN (-1825 3075) $PN BM57
J 0
(-1815 3085);
DISPLAY 0.489362 (-1815 3085);
PAINT MONO (-1815 3085);
FORCEPROP 0 LASTPIN (-1825 3025) $PN BM64
J 0
(-1815 3035);
DISPLAY 0.489362 (-1815 3035);
PAINT MONO (-1815 3035);
FORCEPROP 0 LASTPIN (-1825 2975) $PN BM71
J 0
(-1815 2985);
DISPLAY 0.489362 (-1815 2985);
PAINT MONO (-1815 2985);
FORCEPROP 0 LASTPIN (-1825 2925) $PN BN54
J 0
(-1815 2935);
DISPLAY 0.489362 (-1815 2935);
PAINT MONO (-1815 2935);
FORCEPROP 0 LASTPIN (-1825 2875) $PN BR58
J 0
(-1815 2885);
DISPLAY 0.489362 (-1815 2885);
PAINT MONO (-1815 2885);
FORCEPROP 0 LASTPIN (-1825 2825) $PN BR65
J 0
(-1815 2835);
DISPLAY 0.489362 (-1815 2835);
PAINT MONO (-1815 2835);
FORCEPROP 0 LASTPIN (-1825 2775) $PN BR72
J 0
(-1815 2785);
DISPLAY 0.489362 (-1815 2785);
PAINT MONO (-1815 2785);
FORCEPROP 0 LASTPIN (-1825 2725) $PN BV54
J 0
(-1815 2735);
DISPLAY 0.489362 (-1815 2735);
PAINT MONO (-1815 2735);
FORCEPROP 0 LASTPIN (-1825 2675) $PN BV57
J 0
(-1815 2685);
DISPLAY 0.489362 (-1815 2685);
PAINT MONO (-1815 2685);
FORCEPROP 0 LASTPIN (-1825 2625) $PN BV64
J 0
(-1815 2635);
DISPLAY 0.489362 (-1815 2635);
PAINT MONO (-1815 2635);
FORCEPROP 0 LASTPIN (-1825 2575) $PN BV71
J 0
(-1815 2585);
DISPLAY 0.489362 (-1815 2585);
PAINT MONO (-1815 2585);
FORCEPROP 0 LASTPIN (-1825 2525) $PN CA58
J 0
(-1815 2535);
DISPLAY 0.489362 (-1815 2535);
PAINT MONO (-1815 2535);
FORCEPROP 0 LASTPIN (-1825 2475) $PN CA65
J 0
(-1815 2485);
DISPLAY 0.489362 (-1815 2485);
PAINT MONO (-1815 2485);
FORCEPROP 0 LASTPIN (-1825 2425) $PN CA72
J 0
(-1815 2435);
DISPLAY 0.489362 (-1815 2435);
PAINT MONO (-1815 2435);
FORCEPROP 0 LASTPIN (-1825 2375) $PN CB54
J 0
(-1815 2385);
DISPLAY 0.489362 (-1815 2385);
PAINT MONO (-1815 2385);
FORCEPROP 0 LASTPIN (-1825 2325) $PN CD57
J 0
(-1815 2335);
DISPLAY 0.489362 (-1815 2335);
PAINT MONO (-1815 2335);
FORCEPROP 0 LASTPIN (-1825 2275) $PN CD64
J 0
(-1815 2285);
DISPLAY 0.489362 (-1815 2285);
PAINT MONO (-1815 2285);
FORCEPROP 0 LASTPIN (-1825 2225) $PN CD71
J 0
(-1815 2235);
DISPLAY 0.489362 (-1815 2235);
PAINT MONO (-1815 2235);
FORCEPROP 0 LASTPIN (-1825 2175) $PN CF54
J 0
(-1815 2185);
DISPLAY 0.489362 (-1815 2185);
PAINT MONO (-1815 2185);
FORCEPROP 0 LASTPIN (-1825 2125) $PN CG58
J 0
(-1815 2135);
DISPLAY 0.489362 (-1815 2135);
PAINT MONO (-1815 2135);
FORCEPROP 0 LASTPIN (-1825 2075) $PN CG65
J 0
(-1815 2085);
DISPLAY 0.489362 (-1815 2085);
PAINT MONO (-1815 2085);
FORCEPROP 0 LASTPIN (-1825 2025) $PN CG72
J 0
(-1815 2035);
DISPLAY 0.489362 (-1815 2035);
PAINT MONO (-1815 2035);
FORCEPROP 0 LASTPIN (-1825 1975) $PN CJ54
J 0
(-1815 1985);
DISPLAY 0.489362 (-1815 1985);
PAINT MONO (-1815 1985);
FORCEPROP 0 LASTPIN (-1825 1925) $PN CK57
J 0
(-1815 1935);
DISPLAY 0.489362 (-1815 1935);
PAINT MONO (-1815 1935);
FORCEPROP 0 LASTPIN (-1825 1875) $PN CK64
J 0
(-1815 1885);
DISPLAY 0.489362 (-1815 1885);
PAINT MONO (-1815 1885);
FORCEPROP 0 LASTPIN (-1825 1825) $PN CK71
J 0
(-1815 1835);
DISPLAY 0.489362 (-1815 1835);
PAINT MONO (-1815 1835);
FORCEPROP 0 LASTPIN (-1825 1775) $PN CM54
J 0
(-1815 1785);
DISPLAY 0.489362 (-1815 1785);
PAINT MONO (-1815 1785);
FORCEPROP 0 LASTPIN (-1825 1725) $PN CN58
J 0
(-1815 1735);
DISPLAY 0.489362 (-1815 1735);
PAINT MONO (-1815 1735);
FORCEPROP 0 LASTPIN (-1825 1675) $PN CN65
J 0
(-1815 1685);
DISPLAY 0.489362 (-1815 1685);
PAINT MONO (-1815 1685);
FORCEPROP 0 LASTPIN (-1825 1625) $PN CN72
J 0
(-1815 1635);
DISPLAY 0.489362 (-1815 1635);
PAINT MONO (-1815 1635);
FORCEPROP 0 LASTPIN (-1825 1575) $PN CT54
J 0
(-1815 1585);
DISPLAY 0.489362 (-1815 1585);
PAINT MONO (-1815 1585);
FORCEPROP 0 LASTPIN (-1825 1525) $PN CT57
J 0
(-1815 1535);
DISPLAY 0.489362 (-1815 1535);
PAINT MONO (-1815 1535);
FORCEPROP 0 LASTPIN (-1825 1475) $PN CT64
J 0
(-1815 1485);
DISPLAY 0.489362 (-1815 1485);
PAINT MONO (-1815 1485);
FORCEPROP 0 LASTPIN (-1825 1425) $PN CT71
J 0
(-1815 1435);
DISPLAY 0.489362 (-1815 1435);
PAINT MONO (-1815 1435);
FORCEPROP 0 LASTPIN (-1825 1375) $PN CW58
J 0
(-1815 1385);
DISPLAY 0.489362 (-1815 1385);
PAINT MONO (-1815 1385);
FORCEPROP 0 LASTPIN (-1825 1325) $PN CW65
J 0
(-1815 1335);
DISPLAY 0.489362 (-1815 1335);
PAINT MONO (-1815 1335);
FORCEPROP 0 LASTPIN (-1825 1275) $PN CW72
J 0
(-1815 1285);
DISPLAY 0.489362 (-1815 1285);
PAINT MONO (-1815 1285);
FORCEPROP 0 LASTPIN (-1825 1225) $PN CY54
J 0
(-1815 1235);
DISPLAY 0.489362 (-1815 1235);
PAINT MONO (-1815 1235);
FORCEPROP 0 LASTPIN (-1825 1175) $PN DB57
J 0
(-1815 1185);
DISPLAY 0.489362 (-1815 1185);
PAINT MONO (-1815 1185);
FORCEPROP 0 LASTPIN (-1825 1125) $PN DB64
J 0
(-1815 1135);
DISPLAY 0.489362 (-1815 1135);
PAINT MONO (-1815 1135);
FORCEPROP 0 LASTPIN (-1825 1075) $PN DB71
J 0
(-1815 1085);
DISPLAY 0.489362 (-1815 1085);
PAINT MONO (-1815 1085);
FORCEPROP 0 LASTPIN (-1825 1025) $PN DE58
J 0
(-1815 1035);
DISPLAY 0.489362 (-1815 1035);
PAINT MONO (-1815 1035);
FORCEPROP 0 LASTPIN (-1825 975) $PN DE65
J 0
(-1815 985);
DISPLAY 0.489362 (-1815 985);
PAINT MONO (-1815 985);
FORCEPROP 0 LASTPIN (-1825 925) $PN DE72
J 0
(-1815 935);
DISPLAY 0.489362 (-1815 935);
PAINT MONO (-1815 935);
FORCEPROP 0 LASTPIN (-1825 875) $PN DG64
J 0
(-1815 885);
DISPLAY 0.489362 (-1815 885);
PAINT MONO (-1815 885);
FORCEPROP 0 LASTPIN (-1825 825) $PN DG71
J 0
(-1815 835);
DISPLAY 0.489362 (-1815 835);
PAINT MONO (-1815 835);
FORCEPROP 0 LASTPIN (-1825 6525) $PN H57
J 0
(-1815 6535);
DISPLAY 0.489362 (-1815 6535);
PAINT MONO (-1815 6535);
FORCEPROP 0 LASTPIN (-1825 6475) $PN H64
J 0
(-1815 6485);
DISPLAY 0.489362 (-1815 6485);
PAINT MONO (-1815 6485);
FORCEPROP 0 LASTPIN (-1825 6425) $PN H71
J 0
(-1815 6435);
DISPLAY 0.489362 (-1815 6435);
PAINT MONO (-1815 6435);
FORCEPROP 0 LASTPIN (-1825 6375) $PN K54
J 0
(-1815 6385);
DISPLAY 0.489362 (-1815 6385);
PAINT MONO (-1815 6385);
FORCEPROP 0 LASTPIN (-1825 6325) $PN L58
J 0
(-1815 6335);
DISPLAY 0.489362 (-1815 6335);
PAINT MONO (-1815 6335);
FORCEPROP 0 LASTPIN (-1825 6275) $PN L65
J 0
(-1815 6285);
DISPLAY 0.489362 (-1815 6285);
PAINT MONO (-1815 6285);
FORCEPROP 0 LASTPIN (-1825 6225) $PN L72
J 0
(-1815 6235);
DISPLAY 0.489362 (-1815 6235);
PAINT MONO (-1815 6235);
FORCEPROP 0 LASTPIN (-1825 6175) $PN P54
J 0
(-1815 6185);
DISPLAY 0.489362 (-1815 6185);
PAINT MONO (-1815 6185);
FORCEPROP 0 LASTPIN (-1825 6125) $PN P57
J 0
(-1815 6135);
DISPLAY 0.489362 (-1815 6135);
PAINT MONO (-1815 6135);
FORCEPROP 0 LASTPIN (-1825 6075) $PN P64
J 0
(-1815 6085);
DISPLAY 0.489362 (-1815 6085);
PAINT MONO (-1815 6085);
FORCEPROP 0 LASTPIN (-1825 6025) $PN P71
J 0
(-1815 6035);
DISPLAY 0.489362 (-1815 6035);
PAINT MONO (-1815 6035);
FORCEPROP 0 LASTPIN (-1825 5975) $PN U58
J 0
(-1815 5985);
DISPLAY 0.489362 (-1815 5985);
PAINT MONO (-1815 5985);
FORCEPROP 0 LASTPIN (-1825 5925) $PN U65
J 0
(-1815 5935);
DISPLAY 0.489362 (-1815 5935);
PAINT MONO (-1815 5935);
FORCEPROP 0 LASTPIN (-1825 5875) $PN U72
J 0
(-1815 5885);
DISPLAY 0.489362 (-1815 5885);
PAINT MONO (-1815 5885);
FORCEPROP 0 LASTPIN (-1825 5825) $PN V54
J 0
(-1815 5835);
DISPLAY 0.489362 (-1815 5835);
PAINT MONO (-1815 5835);
FORCEPROP 0 LASTPIN (-1825 5775) $PN Y57
J 0
(-1815 5785);
DISPLAY 0.489362 (-1815 5785);
PAINT MONO (-1815 5785);
FORCEPROP 0 LASTPIN (-1825 5725) $PN Y64
J 0
(-1815 5735);
DISPLAY 0.489362 (-1815 5735);
PAINT MONO (-1815 5735);
FORCEPROP 0 LASTPIN (-1825 5675) $PN Y71
J 0
(-1815 5685);
DISPLAY 0.489362 (-1815 5685);
PAINT MONO (-1815 5685);
FORCEPROP 2 LAST PART_TYPE SMLF
J 0
(-2825 6650);
DISPLAY 1.021277 (-2825 6650);
FORCEPROP 1 LAST MATERIAL IO
J 0
(-2970 6657);
DISPLAY 0.489362 (-2970 6657);
PAINT SKYBLUE (-2970 6657);
FORCEPROP 2 LAST VALUE SOCKET6096_13568-001
J 0
(-2600 6650);
DISPLAY 0.489362 (-2600 6650);
PAINT SKYBLUE (-2600 6650);
FORCEPROP 2 LAST CDS_LIB pure_quanta
J 0
(-2475 3550);
DISPLAY INVISIBLE (-2475 3550);
FORCEPROP 1 LAST CDS_LMAN_SYM_OUTLINE -500,3075,500,-3075
J 0
(-2475 3550);
DISPLAY 0.468085 (-2475 3550);
PAINT GREEN (-2475 3550);
DISPLAY INVISIBLE (-2475 3550);
FORCEPROP 1 LAST NEEDS_NO_SIZE TRUE
J 0
(-2475 3550);
DISPLAY 0.723404 (-2475 3550);
PAINT GREEN (-2475 3550);
DISPLAY INVISIBLE (-2475 3550);
FORCEPROP 1 LAST PATH I28
J 0
(-2475 3550);
DISPLAY 0.723404 (-2475 3550);
PAINT GREEN (-2475 3550);
DISPLAY INVISIBLE (-2475 3550);
FORCEPROP 1 LAST PART_NUMBER DGA^6000030
J 0
(-2825 6700);
DISPLAY 0.489362 (-2825 6700);
PAINT SKYBLUE (-2825 6700);
DISPLAY INVISIBLE (-2825 6700);
FORCEADD GENOA_SP5..23
(-725 4350);
FORCEPROP 1 LAST LOCATION U25
J 0
(-1275 6500);
DISPLAY 0.489362 (-1275 6500);
PAINT SKYBLUE (-1275 6500);
FORCEPROP 0 LAST $SEC 23
J 0
(-1250 6700);
DISPLAY 0.680851 (-1250 6700);
PAINT MONO (-1250 6700);
DISPLAY INVISIBLE (-1250 6700);
FORCEPROP 0 LAST CDS_SEC 23
J 0
(-750 6625);
DISPLAY 1.021277 (-750 6625);
DISPLAY INVISIBLE (-750 6625);
FORCEPROP 0 LASTPIN (-1425 5700) $PN A31
J 2
(-1435 5710);
DISPLAY 0.489362 (-1435 5710);
PAINT MONO (-1435 5710);
FORCEPROP 0 LASTPIN (-1425 5650) $PN A35
J 2
(-1435 5660);
DISPLAY 0.489362 (-1435 5660);
PAINT MONO (-1435 5660);
FORCEPROP 0 LASTPIN (-1425 5600) $PN A41
J 2
(-1435 5610);
DISPLAY 0.489362 (-1435 5610);
PAINT MONO (-1435 5610);
FORCEPROP 0 LASTPIN (-1425 5550) $PN A42
J 2
(-1435 5560);
DISPLAY 0.489362 (-1435 5560);
PAINT MONO (-1435 5560);
FORCEPROP 0 LASTPIN (-1425 5500) $PN A45
J 2
(-1435 5510);
DISPLAY 0.489362 (-1435 5510);
PAINT MONO (-1435 5510);
FORCEPROP 0 LASTPIN (-1425 5450) $PN A48
J 2
(-1435 5460);
DISPLAY 0.489362 (-1435 5460);
PAINT MONO (-1435 5460);
FORCEPROP 0 LASTPIN (-1425 5400) $PN A50
J 2
(-1435 5410);
DISPLAY 0.489362 (-1435 5410);
PAINT MONO (-1435 5410);
FORCEPROP 0 LASTPIN (-1425 5350) $PN A51
J 2
(-1435 5360);
DISPLAY 0.489362 (-1435 5360);
PAINT MONO (-1435 5360);
FORCEPROP 0 LASTPIN (-1425 5300) $PN A54
J 2
(-1435 5310);
DISPLAY 0.489362 (-1435 5310);
PAINT MONO (-1435 5310);
FORCEPROP 0 LASTPIN (-1425 5250) $PN A55
J 2
(-1435 5260);
DISPLAY 0.489362 (-1435 5260);
PAINT MONO (-1435 5260);
FORCEPROP 0 LASTPIN (-1425 5200) $PN A56
J 2
(-1435 5210);
DISPLAY 0.489362 (-1435 5210);
PAINT MONO (-1435 5210);
FORCEPROP 0 LASTPIN (-1425 5150) $PN A57
J 2
(-1435 5160);
DISPLAY 0.489362 (-1435 5160);
PAINT MONO (-1435 5160);
FORCEPROP 0 LASTPIN (-1425 5100) $PN A59
J 2
(-1435 5110);
DISPLAY 0.489362 (-1435 5110);
PAINT MONO (-1435 5110);
FORCEPROP 0 LASTPIN (-1425 5050) $PN A60
J 2
(-1435 5060);
DISPLAY 0.489362 (-1435 5060);
PAINT MONO (-1435 5060);
FORCEPROP 0 LASTPIN (-1425 5000) $PN B40
J 2
(-1435 5010);
DISPLAY 0.489362 (-1435 5010);
PAINT MONO (-1435 5010);
FORCEPROP 0 LASTPIN (-1425 4100) $PN BD4
J 2
(-1435 4110);
DISPLAY 0.489362 (-1435 4110);
PAINT MONO (-1435 4110);
FORCEPROP 0 LASTPIN (-1425 4050) $PN BD7
J 2
(-1435 4060);
DISPLAY 0.489362 (-1435 4060);
PAINT MONO (-1435 4060);
FORCEPROP 0 LASTPIN (-1425 4000) $PN BD11
J 2
(-1435 4010);
DISPLAY 0.489362 (-1435 4010);
PAINT MONO (-1435 4010);
FORCEPROP 0 LASTPIN (-1425 3950) $PN BD14
J 2
(-1435 3960);
DISPLAY 0.489362 (-1435 3960);
PAINT MONO (-1435 3960);
FORCEPROP 0 LASTPIN (-1425 3900) $PN BD18
J 2
(-1435 3910);
DISPLAY 0.489362 (-1435 3910);
PAINT MONO (-1435 3910);
FORCEPROP 0 LASTPIN (-1425 3850) $PN BD21
J 2
(-1435 3860);
DISPLAY 0.489362 (-1435 3860);
PAINT MONO (-1435 3860);
FORCEPROP 0 LASTPIN (-1425 3800) $PN BD55
J 2
(-1435 3810);
DISPLAY 0.489362 (-1435 3810);
PAINT MONO (-1435 3810);
FORCEPROP 0 LASTPIN (-1425 3750) $PN BD58
J 2
(-1435 3760);
DISPLAY 0.489362 (-1435 3760);
PAINT MONO (-1435 3760);
FORCEPROP 0 LASTPIN (-1425 3700) $PN BD62
J 2
(-1435 3710);
DISPLAY 0.489362 (-1435 3710);
PAINT MONO (-1435 3710);
FORCEPROP 0 LASTPIN (-1425 3650) $PN BD65
J 2
(-1435 3660);
DISPLAY 0.489362 (-1435 3660);
PAINT MONO (-1435 3660);
FORCEPROP 0 LASTPIN (-1425 3600) $PN BD69
J 2
(-1435 3610);
DISPLAY 0.489362 (-1435 3610);
PAINT MONO (-1435 3610);
FORCEPROP 0 LASTPIN (-1425 3550) $PN BD72
J 2
(-1435 3560);
DISPLAY 0.489362 (-1435 3560);
PAINT MONO (-1435 3560);
FORCEPROP 0 LASTPIN (-1425 4950) $PN C31
J 2
(-1435 4960);
DISPLAY 0.489362 (-1435 4960);
PAINT MONO (-1435 4960);
FORCEPROP 0 LASTPIN (-1425 4900) $PN C34
J 2
(-1435 4910);
DISPLAY 0.489362 (-1435 4910);
PAINT MONO (-1435 4910);
FORCEPROP 0 LASTPIN (-1425 4850) $PN C35
J 2
(-1435 4860);
DISPLAY 0.489362 (-1435 4860);
PAINT MONO (-1435 4860);
FORCEPROP 0 LASTPIN (-1425 4800) $PN C53
J 2
(-1435 4810);
DISPLAY 0.489362 (-1435 4810);
PAINT MONO (-1435 4810);
FORCEPROP 0 LASTPIN (-1425 4750) $PN C54
J 2
(-1435 4760);
DISPLAY 0.489362 (-1435 4760);
PAINT MONO (-1435 4760);
FORCEPROP 0 LASTPIN (-1425 4700) $PN D4
J 2
(-1435 4710);
DISPLAY 0.489362 (-1435 4710);
PAINT MONO (-1435 4710);
FORCEPROP 0 LASTPIN (-1425 4650) $PN D8
J 2
(-1435 4660);
DISPLAY 0.489362 (-1435 4660);
PAINT MONO (-1435 4660);
FORCEPROP 0 LASTPIN (-1425 4600) $PN D11
J 2
(-1435 4610);
DISPLAY 0.489362 (-1435 4610);
PAINT MONO (-1435 4610);
FORCEPROP 0 LASTPIN (-1425 4550) $PN D22
J 2
(-1435 4560);
DISPLAY 0.489362 (-1435 4560);
PAINT MONO (-1435 4560);
FORCEPROP 0 LASTPIN (-1425 4500) $PN D34
J 2
(-1435 4510);
DISPLAY 0.489362 (-1435 4510);
PAINT MONO (-1435 4510);
FORCEPROP 0 LASTPIN (-1425 4450) $PN D36
J 2
(-1435 4460);
DISPLAY 0.489362 (-1435 4460);
PAINT MONO (-1435 4460);
FORCEPROP 0 LASTPIN (-1425 4400) $PN D58
J 2
(-1435 4410);
DISPLAY 0.489362 (-1435 4410);
PAINT MONO (-1435 4410);
FORCEPROP 0 LASTPIN (-1425 4350) $PN D62
J 2
(-1435 4360);
DISPLAY 0.489362 (-1435 4360);
PAINT MONO (-1435 4360);
FORCEPROP 0 LASTPIN (-1425 4300) $PN D65
J 2
(-1435 4310);
DISPLAY 0.489362 (-1435 4310);
PAINT MONO (-1435 4310);
FORCEPROP 0 LASTPIN (-1425 4250) $PN D72
J 2
(-1435 4260);
DISPLAY 0.489362 (-1435 4260);
PAINT MONO (-1435 4260);
FORCEPROP 0 LASTPIN (-1425 3500) $PN DG17
J 2
(-1435 3510);
DISPLAY 0.489362 (-1435 3510);
PAINT MONO (-1435 3510);
FORCEPROP 0 LASTPIN (-1425 3450) $PN DH17
J 2
(-1435 3460);
DISPLAY 0.489362 (-1435 3460);
PAINT MONO (-1435 3460);
FORCEPROP 0 LASTPIN (-1425 3400) $PN DH21
J 2
(-1435 3410);
DISPLAY 0.489362 (-1435 3410);
PAINT MONO (-1435 3410);
FORCEPROP 0 LASTPIN (-1425 3350) $PN DJ4
J 2
(-1435 3360);
DISPLAY 0.489362 (-1435 3360);
PAINT MONO (-1435 3360);
FORCEPROP 0 LASTPIN (-1425 4200) $PN E33
J 2
(-1435 4210);
DISPLAY 0.489362 (-1435 4210);
PAINT MONO (-1435 4210);
FORCEPROP 0 LASTPIN (-1425 4150) $PN E36
J 2
(-1435 4160);
DISPLAY 0.489362 (-1435 4160);
PAINT MONO (-1435 4160);
FORCEPROP 0 LASTPIN (-1425 3150) $PN C58
J 2
(-1435 3160);
DISPLAY 0.489362 (-1435 3160);
PAINT MONO (-1435 3160);
FORCEPROP 0 LASTPIN (-1425 2900) $PN DH13
J 2
(-1435 2910);
DISPLAY 0.489362 (-1435 2910);
PAINT MONO (-1435 2910);
FORCEPROP 0 LASTPIN (-1425 3000) $PN DF41
J 2
(-1435 3010);
DISPLAY 0.489362 (-1435 3010);
PAINT MONO (-1435 3010);
FORCEPROP 0 LASTPIN (-1425 3200) $PN C23
J 2
(-1435 3210);
DISPLAY 0.489362 (-1435 3210);
PAINT MONO (-1435 3210);
FORCEPROP 0 LASTPIN (-1425 3100) $PN C59
J 2
(-1435 3110);
DISPLAY 0.489362 (-1435 3110);
PAINT MONO (-1435 3110);
FORCEPROP 0 LASTPIN (-1425 2850) $PN DH14
J 2
(-1435 2860);
DISPLAY 0.489362 (-1435 2860);
PAINT MONO (-1435 2860);
FORCEPROP 0 LASTPIN (-1425 2950) $PN DG42
J 2
(-1435 2960);
DISPLAY 0.489362 (-1435 2960);
PAINT MONO (-1435 2960);
FORCEPROP 0 LASTPIN (-1425 3050) $PN D23
J 2
(-1435 3060);
DISPLAY 0.489362 (-1435 3060);
PAINT MONO (-1435 3060);
FORCEPROP 0 LASTPIN (-1425 2700) $PN B36
J 2
(-1435 2710);
DISPLAY 0.489362 (-1435 2710);
PAINT MONO (-1435 2710);
FORCEPROP 0 LASTPIN (-1425 2800) $PN DJ57
J 2
(-1435 2810);
DISPLAY 0.489362 (-1435 2810);
PAINT MONO (-1435 2810);
FORCEPROP 2 LAST PART_TYPE SMLF
J 0
(-1275 6650);
DISPLAY 1.021277 (-1275 6650);
FORCEPROP 1 LAST MATERIAL IO
J 0
(-1270 6382);
DISPLAY 0.489362 (-1270 6382);
PAINT SKYBLUE (-1270 6382);
FORCEPROP 2 LAST VALUE SOCKET6096_13568-001
J 0
(-1275 6450);
DISPLAY 0.489362 (-1275 6450);
PAINT SKYBLUE (-1275 6450);
FORCEPROP 1 LAST CDS_LMAN_SYM_OUTLINE -550,2000,550,-2000
J 0
(-725 4350);
DISPLAY 0.468085 (-725 4350);
PAINT GREEN (-725 4350);
DISPLAY INVISIBLE (-725 4350);
FORCEPROP 2 LAST CDS_LIB pure_quanta
J 0
(-725 4350);
DISPLAY INVISIBLE (-725 4350);
FORCEPROP 1 LAST NEEDS_NO_SIZE TRUE
J 0
(-725 4350);
DISPLAY 0.723404 (-725 4350);
PAINT GREEN (-725 4350);
DISPLAY INVISIBLE (-725 4350);
FORCEPROP 1 LAST PATH I29
J 0
(-725 4350);
DISPLAY 0.723404 (-725 4350);
PAINT GREEN (-725 4350);
DISPLAY INVISIBLE (-725 4350);
FORCEPROP 1 LAST PART_NUMBER DGA^6000030
J 0
(-1275 6575);
DISPLAY 0.489362 (-1275 6575);
PAINT SKYBLUE (-1275 6575);
DISPLAY INVISIBLE (-1275 6575);
FORCEADD VCC_CORE..1
(-1675 6625);
FORCEPROP 3 LASTPIN (-1675 6575) SIG_NAME PVDDIO_P0\g
J 0
(-1665 6585);
DISPLAY 0.659574 (-1665 6585);
PAINT MONO (-1665 6585);
DISPLAY INVISIBLE (-1665 6585);
FORCEPROP 1 LAST HDL_POWER PVDDIO_P0
J 1
(-1675 6675);
DISPLAY 0.489362 (-1675 6675);
PAINT GREEN (-1675 6675);
FORCEPROP 2 LAST CDS_LIB pure_quanta_power
J 0
(-1675 6625);
DISPLAY INVISIBLE (-1675 6625);
FORCEPROP 1 LAST PATH I40
J 0
(-1625 6650);
DISPLAY 0.872340 (-1625 6650);
PAINT AQUA (-1625 6650);
DISPLAY INVISIBLE (-1625 6650);
FORCEADD UNIVERSAL_POWER..1
(-1475 825);
FORCEPROP 3 LASTPIN (-1475 775) SIG_NAME P1V5_BAT\g
J 0
(-1465 785);
DISPLAY 0.659574 (-1465 785);
PAINT MONO (-1465 785);
DISPLAY INVISIBLE (-1465 785);
FORCEPROP 1 LAST HDL_POWER P1V5_BAT
J 1
(-1475 875);
DISPLAY 0.489362 (-1475 875);
PAINT GREEN (-1475 875);
FORCEPROP 2 LAST CDS_LIB pure_quanta_power
J 0
(-1475 825);
DISPLAY INVISIBLE (-1475 825);
FORCEPROP 1 LAST PATH I41
J 0
(-1425 850);
DISPLAY 0.872340 (-1425 850);
PAINT AQUA (-1425 850);
DISPLAY INVISIBLE (-1425 850);
FORCEADD GENOA_SP5..24
(-8050 3325);
FORCEPROP 1 LAST LOCATION U25
J 0
(-8550 6600);
DISPLAY 0.489362 (-8550 6600);
PAINT SKYBLUE (-8550 6600);
FORCEPROP 0 LAST $SEC 24
J 0
(-8525 6825);
DISPLAY 0.680851 (-8525 6825);
PAINT MONO (-8525 6825);
DISPLAY INVISIBLE (-8525 6825);
FORCEPROP 0 LAST CDS_SEC 24
J 0
(-8550 6700);
DISPLAY 1.021277 (-8550 6700);
DISPLAY INVISIBLE (-8550 6700);
FORCEPROP 0 LASTPIN (-7400 5925) $PN AB23
J 0
(-7390 5935);
DISPLAY 0.489362 (-7390 5935);
PAINT MONO (-7390 5935);
FORCEPROP 0 LASTPIN (-7400 5875) $PN AB24
J 0
(-7390 5885);
DISPLAY 0.489362 (-7390 5885);
PAINT MONO (-7390 5885);
FORCEPROP 0 LASTPIN (-7400 5825) $PN AB26
J 0
(-7390 5835);
DISPLAY 0.489362 (-7390 5835);
PAINT MONO (-7390 5835);
FORCEPROP 0 LASTPIN (-7400 5775) $PN AB27
J 0
(-7390 5785);
DISPLAY 0.489362 (-7390 5785);
PAINT MONO (-7390 5785);
FORCEPROP 0 LASTPIN (-7400 5725) $PN AB29
J 0
(-7390 5735);
DISPLAY 0.489362 (-7390 5735);
PAINT MONO (-7390 5735);
FORCEPROP 0 LASTPIN (-7400 5675) $PN AB30
J 0
(-7390 5685);
DISPLAY 0.489362 (-7390 5685);
PAINT MONO (-7390 5685);
FORCEPROP 0 LASTPIN (-7400 5625) $PN AB32
J 0
(-7390 5635);
DISPLAY 0.489362 (-7390 5635);
PAINT MONO (-7390 5635);
FORCEPROP 0 LASTPIN (-7400 5575) $PN AB33
J 0
(-7390 5585);
DISPLAY 0.489362 (-7390 5585);
PAINT MONO (-7390 5585);
FORCEPROP 0 LASTPIN (-7400 5525) $PN AB43
J 0
(-7390 5535);
DISPLAY 0.489362 (-7390 5535);
PAINT MONO (-7390 5535);
FORCEPROP 0 LASTPIN (-7400 5475) $PN AB44
J 0
(-7390 5485);
DISPLAY 0.489362 (-7390 5485);
PAINT MONO (-7390 5485);
FORCEPROP 0 LASTPIN (-7400 5425) $PN AB46
J 0
(-7390 5435);
DISPLAY 0.489362 (-7390 5435);
PAINT MONO (-7390 5435);
FORCEPROP 0 LASTPIN (-7400 5375) $PN AB47
J 0
(-7390 5385);
DISPLAY 0.489362 (-7390 5385);
PAINT MONO (-7390 5385);
FORCEPROP 0 LASTPIN (-7400 5325) $PN AB49
J 0
(-7390 5335);
DISPLAY 0.489362 (-7390 5335);
PAINT MONO (-7390 5335);
FORCEPROP 0 LASTPIN (-7400 5275) $PN AB50
J 0
(-7390 5285);
DISPLAY 0.489362 (-7390 5285);
PAINT MONO (-7390 5285);
FORCEPROP 0 LASTPIN (-7400 5225) $PN AB52
J 0
(-7390 5235);
DISPLAY 0.489362 (-7390 5235);
PAINT MONO (-7390 5235);
FORCEPROP 0 LASTPIN (-7400 5175) $PN AB53
J 0
(-7390 5185);
DISPLAY 0.489362 (-7390 5185);
PAINT MONO (-7390 5185);
FORCEPROP 0 LASTPIN (-7400 5125) $PN AC35
J 0
(-7390 5135);
DISPLAY 0.489362 (-7390 5135);
PAINT MONO (-7390 5135);
FORCEPROP 0 LASTPIN (-7400 5075) $PN AC36
J 0
(-7390 5085);
DISPLAY 0.489362 (-7390 5085);
PAINT MONO (-7390 5085);
FORCEPROP 0 LASTPIN (-7400 5025) $PN AC40
J 0
(-7390 5035);
DISPLAY 0.489362 (-7390 5035);
PAINT MONO (-7390 5035);
FORCEPROP 0 LASTPIN (-7400 4975) $PN AC41
J 0
(-7390 4985);
DISPLAY 0.489362 (-7390 4985);
PAINT MONO (-7390 4985);
FORCEPROP 0 LASTPIN (-7400 4925) $PN AF23
J 0
(-7390 4935);
DISPLAY 0.489362 (-7390 4935);
PAINT MONO (-7390 4935);
FORCEPROP 0 LASTPIN (-7400 4875) $PN AF24
J 0
(-7390 4885);
DISPLAY 0.489362 (-7390 4885);
PAINT MONO (-7390 4885);
FORCEPROP 0 LASTPIN (-7400 4825) $PN AF26
J 0
(-7390 4835);
DISPLAY 0.489362 (-7390 4835);
PAINT MONO (-7390 4835);
FORCEPROP 0 LASTPIN (-7400 4775) $PN AF27
J 0
(-7390 4785);
DISPLAY 0.489362 (-7390 4785);
PAINT MONO (-7390 4785);
FORCEPROP 0 LASTPIN (-7400 4725) $PN AF29
J 0
(-7390 4735);
DISPLAY 0.489362 (-7390 4735);
PAINT MONO (-7390 4735);
FORCEPROP 0 LASTPIN (-7400 4675) $PN AF30
J 0
(-7390 4685);
DISPLAY 0.489362 (-7390 4685);
PAINT MONO (-7390 4685);
FORCEPROP 0 LASTPIN (-7400 4625) $PN AF32
J 0
(-7390 4635);
DISPLAY 0.489362 (-7390 4635);
PAINT MONO (-7390 4635);
FORCEPROP 0 LASTPIN (-7400 4575) $PN AF33
J 0
(-7390 4585);
DISPLAY 0.489362 (-7390 4585);
PAINT MONO (-7390 4585);
FORCEPROP 0 LASTPIN (-7400 4525) $PN AF43
J 0
(-7390 4535);
DISPLAY 0.489362 (-7390 4535);
PAINT MONO (-7390 4535);
FORCEPROP 0 LASTPIN (-7400 4475) $PN AF44
J 0
(-7390 4485);
DISPLAY 0.489362 (-7390 4485);
PAINT MONO (-7390 4485);
FORCEPROP 0 LASTPIN (-7400 4425) $PN AF46
J 0
(-7390 4435);
DISPLAY 0.489362 (-7390 4435);
PAINT MONO (-7390 4435);
FORCEPROP 0 LASTPIN (-7400 4375) $PN AF47
J 0
(-7390 4385);
DISPLAY 0.489362 (-7390 4385);
PAINT MONO (-7390 4385);
FORCEPROP 0 LASTPIN (-7400 4325) $PN AF49
J 0
(-7390 4335);
DISPLAY 0.489362 (-7390 4335);
PAINT MONO (-7390 4335);
FORCEPROP 0 LASTPIN (-7400 4275) $PN AF50
J 0
(-7390 4285);
DISPLAY 0.489362 (-7390 4285);
PAINT MONO (-7390 4285);
FORCEPROP 0 LASTPIN (-7400 4225) $PN AF52
J 0
(-7390 4235);
DISPLAY 0.489362 (-7390 4235);
PAINT MONO (-7390 4235);
FORCEPROP 0 LASTPIN (-7400 4175) $PN AF53
J 0
(-7390 4185);
DISPLAY 0.489362 (-7390 4185);
PAINT MONO (-7390 4185);
FORCEPROP 0 LASTPIN (-7400 4125) $PN AG35
J 0
(-7390 4135);
DISPLAY 0.489362 (-7390 4135);
PAINT MONO (-7390 4135);
FORCEPROP 0 LASTPIN (-7400 4075) $PN AG36
J 0
(-7390 4085);
DISPLAY 0.489362 (-7390 4085);
PAINT MONO (-7390 4085);
FORCEPROP 0 LASTPIN (-7400 4025) $PN AG40
J 0
(-7390 4035);
DISPLAY 0.489362 (-7390 4035);
PAINT MONO (-7390 4035);
FORCEPROP 0 LASTPIN (-7400 3975) $PN AG41
J 0
(-7390 3985);
DISPLAY 0.489362 (-7390 3985);
PAINT MONO (-7390 3985);
FORCEPROP 0 LASTPIN (-7400 3925) $PN AK23
J 0
(-7390 3935);
DISPLAY 0.489362 (-7390 3935);
PAINT MONO (-7390 3935);
FORCEPROP 0 LASTPIN (-7400 3875) $PN AK24
J 0
(-7390 3885);
DISPLAY 0.489362 (-7390 3885);
PAINT MONO (-7390 3885);
FORCEPROP 0 LASTPIN (-7400 3825) $PN AK26
J 0
(-7390 3835);
DISPLAY 0.489362 (-7390 3835);
PAINT MONO (-7390 3835);
FORCEPROP 0 LASTPIN (-7400 3775) $PN AK27
J 0
(-7390 3785);
DISPLAY 0.489362 (-7390 3785);
PAINT MONO (-7390 3785);
FORCEPROP 0 LASTPIN (-7400 3725) $PN AK29
J 0
(-7390 3735);
DISPLAY 0.489362 (-7390 3735);
PAINT MONO (-7390 3735);
FORCEPROP 0 LASTPIN (-7400 3675) $PN AK30
J 0
(-7390 3685);
DISPLAY 0.489362 (-7390 3685);
PAINT MONO (-7390 3685);
FORCEPROP 0 LASTPIN (-7400 3625) $PN AK32
J 0
(-7390 3635);
DISPLAY 0.489362 (-7390 3635);
PAINT MONO (-7390 3635);
FORCEPROP 0 LASTPIN (-7400 3575) $PN AK33
J 0
(-7390 3585);
DISPLAY 0.489362 (-7390 3585);
PAINT MONO (-7390 3585);
FORCEPROP 0 LASTPIN (-7400 3525) $PN AK43
J 0
(-7390 3535);
DISPLAY 0.489362 (-7390 3535);
PAINT MONO (-7390 3535);
FORCEPROP 0 LASTPIN (-7400 3475) $PN AK44
J 0
(-7390 3485);
DISPLAY 0.489362 (-7390 3485);
PAINT MONO (-7390 3485);
FORCEPROP 0 LASTPIN (-7400 3425) $PN AK46
J 0
(-7390 3435);
DISPLAY 0.489362 (-7390 3435);
PAINT MONO (-7390 3435);
FORCEPROP 0 LASTPIN (-7400 3375) $PN AK47
J 0
(-7390 3385);
DISPLAY 0.489362 (-7390 3385);
PAINT MONO (-7390 3385);
FORCEPROP 0 LASTPIN (-7400 3325) $PN AK49
J 0
(-7390 3335);
DISPLAY 0.489362 (-7390 3335);
PAINT MONO (-7390 3335);
FORCEPROP 0 LASTPIN (-7400 3275) $PN AK50
J 0
(-7390 3285);
DISPLAY 0.489362 (-7390 3285);
PAINT MONO (-7390 3285);
FORCEPROP 0 LASTPIN (-7400 3225) $PN AK52
J 0
(-7390 3235);
DISPLAY 0.489362 (-7390 3235);
PAINT MONO (-7390 3235);
FORCEPROP 0 LASTPIN (-7400 3175) $PN AK53
J 0
(-7390 3185);
DISPLAY 0.489362 (-7390 3185);
PAINT MONO (-7390 3185);
FORCEPROP 0 LASTPIN (-7400 3125) $PN AL35
J 0
(-7390 3135);
DISPLAY 0.489362 (-7390 3135);
PAINT MONO (-7390 3135);
FORCEPROP 0 LASTPIN (-7400 3075) $PN AL36
J 0
(-7390 3085);
DISPLAY 0.489362 (-7390 3085);
PAINT MONO (-7390 3085);
FORCEPROP 0 LASTPIN (-7400 3025) $PN AL40
J 0
(-7390 3035);
DISPLAY 0.489362 (-7390 3035);
PAINT MONO (-7390 3035);
FORCEPROP 0 LASTPIN (-7400 2975) $PN AL41
J 0
(-7390 2985);
DISPLAY 0.489362 (-7390 2985);
PAINT MONO (-7390 2985);
FORCEPROP 0 LASTPIN (-7400 2925) $PN AP23
J 0
(-7390 2935);
DISPLAY 0.489362 (-7390 2935);
PAINT MONO (-7390 2935);
FORCEPROP 0 LASTPIN (-7400 2875) $PN AP24
J 0
(-7390 2885);
DISPLAY 0.489362 (-7390 2885);
PAINT MONO (-7390 2885);
FORCEPROP 0 LASTPIN (-7400 2825) $PN AP26
J 0
(-7390 2835);
DISPLAY 0.489362 (-7390 2835);
PAINT MONO (-7390 2835);
FORCEPROP 0 LASTPIN (-7400 2775) $PN AP27
J 0
(-7390 2785);
DISPLAY 0.489362 (-7390 2785);
PAINT MONO (-7390 2785);
FORCEPROP 0 LASTPIN (-7400 2725) $PN AP29
J 0
(-7390 2735);
DISPLAY 0.489362 (-7390 2735);
PAINT MONO (-7390 2735);
FORCEPROP 0 LASTPIN (-7400 2675) $PN AP30
J 0
(-7390 2685);
DISPLAY 0.489362 (-7390 2685);
PAINT MONO (-7390 2685);
FORCEPROP 0 LASTPIN (-7400 2625) $PN AP32
J 0
(-7390 2635);
DISPLAY 0.489362 (-7390 2635);
PAINT MONO (-7390 2635);
FORCEPROP 0 LASTPIN (-7400 2575) $PN AP33
J 0
(-7390 2585);
DISPLAY 0.489362 (-7390 2585);
PAINT MONO (-7390 2585);
FORCEPROP 0 LASTPIN (-7400 2525) $PN AP43
J 0
(-7390 2535);
DISPLAY 0.489362 (-7390 2535);
PAINT MONO (-7390 2535);
FORCEPROP 0 LASTPIN (-7400 2475) $PN AP44
J 0
(-7390 2485);
DISPLAY 0.489362 (-7390 2485);
PAINT MONO (-7390 2485);
FORCEPROP 0 LASTPIN (-7400 2425) $PN AP46
J 0
(-7390 2435);
DISPLAY 0.489362 (-7390 2435);
PAINT MONO (-7390 2435);
FORCEPROP 0 LASTPIN (-7400 2375) $PN AP47
J 0
(-7390 2385);
DISPLAY 0.489362 (-7390 2385);
PAINT MONO (-7390 2385);
FORCEPROP 0 LASTPIN (-7400 2325) $PN AP49
J 0
(-7390 2335);
DISPLAY 0.489362 (-7390 2335);
PAINT MONO (-7390 2335);
FORCEPROP 0 LASTPIN (-7400 2275) $PN AP50
J 0
(-7390 2285);
DISPLAY 0.489362 (-7390 2285);
PAINT MONO (-7390 2285);
FORCEPROP 0 LASTPIN (-7400 2225) $PN AP52
J 0
(-7390 2235);
DISPLAY 0.489362 (-7390 2235);
PAINT MONO (-7390 2235);
FORCEPROP 0 LASTPIN (-7400 2175) $PN AP53
J 0
(-7390 2185);
DISPLAY 0.489362 (-7390 2185);
PAINT MONO (-7390 2185);
FORCEPROP 0 LASTPIN (-7400 2125) $PN AR23
J 0
(-7390 2135);
DISPLAY 0.489362 (-7390 2135);
PAINT MONO (-7390 2135);
FORCEPROP 0 LASTPIN (-7400 2075) $PN AR25
J 0
(-7390 2085);
DISPLAY 0.489362 (-7390 2085);
PAINT MONO (-7390 2085);
FORCEPROP 0 LASTPIN (-7400 2025) $PN AR27
J 0
(-7390 2035);
DISPLAY 0.489362 (-7390 2035);
PAINT MONO (-7390 2035);
FORCEPROP 0 LASTPIN (-7400 1975) $PN AR29
J 0
(-7390 1985);
DISPLAY 0.489362 (-7390 1985);
PAINT MONO (-7390 1985);
FORCEPROP 0 LASTPIN (-7400 1925) $PN AR31
J 0
(-7390 1935);
DISPLAY 0.489362 (-7390 1935);
PAINT MONO (-7390 1935);
FORCEPROP 0 LASTPIN (-7400 1875) $PN AR33
J 0
(-7390 1885);
DISPLAY 0.489362 (-7390 1885);
PAINT MONO (-7390 1885);
FORCEPROP 0 LASTPIN (-7400 1825) $PN AR35
J 0
(-7390 1835);
DISPLAY 0.489362 (-7390 1835);
PAINT MONO (-7390 1835);
FORCEPROP 0 LASTPIN (-7400 1775) $PN AR40
J 0
(-7390 1785);
DISPLAY 0.489362 (-7390 1785);
PAINT MONO (-7390 1785);
FORCEPROP 0 LASTPIN (-7400 1725) $PN AR42
J 0
(-7390 1735);
DISPLAY 0.489362 (-7390 1735);
PAINT MONO (-7390 1735);
FORCEPROP 0 LASTPIN (-7400 1675) $PN AR44
J 0
(-7390 1685);
DISPLAY 0.489362 (-7390 1685);
PAINT MONO (-7390 1685);
FORCEPROP 0 LASTPIN (-7400 1625) $PN AR46
J 0
(-7390 1635);
DISPLAY 0.489362 (-7390 1635);
PAINT MONO (-7390 1635);
FORCEPROP 0 LASTPIN (-7400 1575) $PN AR48
J 0
(-7390 1585);
DISPLAY 0.489362 (-7390 1585);
PAINT MONO (-7390 1585);
FORCEPROP 0 LASTPIN (-7400 1525) $PN AR50
J 0
(-7390 1535);
DISPLAY 0.489362 (-7390 1535);
PAINT MONO (-7390 1535);
FORCEPROP 0 LASTPIN (-7400 1475) $PN AT24
J 0
(-7390 1485);
DISPLAY 0.489362 (-7390 1485);
PAINT MONO (-7390 1485);
FORCEPROP 0 LASTPIN (-7400 1425) $PN AT26
J 0
(-7390 1435);
DISPLAY 0.489362 (-7390 1435);
PAINT MONO (-7390 1435);
FORCEPROP 0 LASTPIN (-7400 1375) $PN AT28
J 0
(-7390 1385);
DISPLAY 0.489362 (-7390 1385);
PAINT MONO (-7390 1385);
FORCEPROP 0 LASTPIN (-7400 1325) $PN AT30
J 0
(-7390 1335);
DISPLAY 0.489362 (-7390 1335);
PAINT MONO (-7390 1335);
FORCEPROP 0 LASTPIN (-7400 1275) $PN AT32
J 0
(-7390 1285);
DISPLAY 0.489362 (-7390 1285);
PAINT MONO (-7390 1285);
FORCEPROP 0 LASTPIN (-7400 1225) $PN AT34
J 0
(-7390 1235);
DISPLAY 0.489362 (-7390 1235);
PAINT MONO (-7390 1235);
FORCEPROP 0 LASTPIN (-7400 1175) $PN AT36
J 0
(-7390 1185);
DISPLAY 0.489362 (-7390 1185);
PAINT MONO (-7390 1185);
FORCEPROP 0 LASTPIN (-7400 1125) $PN AT39
J 0
(-7390 1135);
DISPLAY 0.489362 (-7390 1135);
PAINT MONO (-7390 1135);
FORCEPROP 0 LASTPIN (-7400 1075) $PN AT41
J 0
(-7390 1085);
DISPLAY 0.489362 (-7390 1085);
PAINT MONO (-7390 1085);
FORCEPROP 0 LASTPIN (-7400 1025) $PN AT43
J 0
(-7390 1035);
DISPLAY 0.489362 (-7390 1035);
PAINT MONO (-7390 1035);
FORCEPROP 0 LASTPIN (-7400 975) $PN AT45
J 0
(-7390 985);
DISPLAY 0.489362 (-7390 985);
PAINT MONO (-7390 985);
FORCEPROP 0 LASTPIN (-7400 925) $PN AT47
J 0
(-7390 935);
DISPLAY 0.489362 (-7390 935);
PAINT MONO (-7390 935);
FORCEPROP 0 LASTPIN (-7400 875) $PN AT49
J 0
(-7390 885);
DISPLAY 0.489362 (-7390 885);
PAINT MONO (-7390 885);
FORCEPROP 0 LASTPIN (-7400 575) $PN AU25
J 0
(-7390 585);
DISPLAY 0.489362 (-7390 585);
PAINT MONO (-7390 585);
FORCEPROP 0 LASTPIN (-7400 825) $PN AU29
J 0
(-7390 835);
DISPLAY 0.489362 (-7390 835);
PAINT MONO (-7390 835);
FORCEPROP 0 LASTPIN (-7400 525) $PN AU33
J 0
(-7390 535);
DISPLAY 0.489362 (-7390 535);
PAINT MONO (-7390 535);
FORCEPROP 0 LASTPIN (-7400 775) $PN AU42
J 0
(-7390 785);
DISPLAY 0.489362 (-7390 785);
PAINT MONO (-7390 785);
FORCEPROP 0 LASTPIN (-7400 675) $PN AU44
J 0
(-7390 685);
DISPLAY 0.489362 (-7390 685);
PAINT MONO (-7390 685);
FORCEPROP 0 LASTPIN (-7400 725) $PN AU46
J 0
(-7390 735);
DISPLAY 0.489362 (-7390 735);
PAINT MONO (-7390 735);
FORCEPROP 0 LASTPIN (-7400 625) $PN AU48
J 0
(-7390 635);
DISPLAY 0.489362 (-7390 635);
PAINT MONO (-7390 635);
FORCEPROP 0 LASTPIN (-8700 6325) $PN B19
J 2
(-8710 6335);
DISPLAY 0.489362 (-8710 6335);
PAINT MONO (-8710 6335);
FORCEPROP 0 LASTPIN (-8700 6275) $PN B20
J 2
(-8710 6285);
DISPLAY 0.489362 (-8710 6285);
PAINT MONO (-8710 6285);
FORCEPROP 0 LASTPIN (-8700 6225) $PN B22
J 2
(-8710 6235);
DISPLAY 0.489362 (-8710 6235);
PAINT MONO (-8710 6235);
FORCEPROP 0 LASTPIN (-8700 6175) $PN B23
J 2
(-8710 6185);
DISPLAY 0.489362 (-8710 6185);
PAINT MONO (-8710 6185);
FORCEPROP 0 LASTPIN (-8700 6125) $PN B25
J 2
(-8710 6135);
DISPLAY 0.489362 (-8710 6135);
PAINT MONO (-8710 6135);
FORCEPROP 0 LASTPIN (-8700 6075) $PN B26
J 2
(-8710 6085);
DISPLAY 0.489362 (-8710 6085);
PAINT MONO (-8710 6085);
FORCEPROP 0 LASTPIN (-8700 6025) $PN B28
J 2
(-8710 6035);
DISPLAY 0.489362 (-8710 6035);
PAINT MONO (-8710 6035);
FORCEPROP 0 LASTPIN (-8700 5975) $PN B29
J 2
(-8710 5985);
DISPLAY 0.489362 (-8710 5985);
PAINT MONO (-8710 5985);
FORCEPROP 0 LASTPIN (-8700 5925) $PN B31
J 2
(-8710 5935);
DISPLAY 0.489362 (-8710 5935);
PAINT MONO (-8710 5935);
FORCEPROP 0 LASTPIN (-8700 5875) $PN B32
J 2
(-8710 5885);
DISPLAY 0.489362 (-8710 5885);
PAINT MONO (-8710 5885);
FORCEPROP 0 LASTPIN (-8700 5825) $PN B34
J 2
(-8710 5835);
DISPLAY 0.489362 (-8710 5835);
PAINT MONO (-8710 5835);
FORCEPROP 0 LASTPIN (-8700 5775) $PN B35
J 2
(-8710 5785);
DISPLAY 0.489362 (-8710 5785);
PAINT MONO (-8710 5785);
FORCEPROP 0 LASTPIN (-8700 5725) $PN B41
J 2
(-8710 5735);
DISPLAY 0.489362 (-8710 5735);
PAINT MONO (-8710 5735);
FORCEPROP 0 LASTPIN (-8700 5675) $PN B42
J 2
(-8710 5685);
DISPLAY 0.489362 (-8710 5685);
PAINT MONO (-8710 5685);
FORCEPROP 0 LASTPIN (-8700 5625) $PN B44
J 2
(-8710 5635);
DISPLAY 0.489362 (-8710 5635);
PAINT MONO (-8710 5635);
FORCEPROP 0 LASTPIN (-8700 5575) $PN B45
J 2
(-8710 5585);
DISPLAY 0.489362 (-8710 5585);
PAINT MONO (-8710 5585);
FORCEPROP 0 LASTPIN (-8700 5525) $PN B47
J 2
(-8710 5535);
DISPLAY 0.489362 (-8710 5535);
PAINT MONO (-8710 5535);
FORCEPROP 0 LASTPIN (-8700 5475) $PN B48
J 2
(-8710 5485);
DISPLAY 0.489362 (-8710 5485);
PAINT MONO (-8710 5485);
FORCEPROP 0 LASTPIN (-8700 5425) $PN B50
J 2
(-8710 5435);
DISPLAY 0.489362 (-8710 5435);
PAINT MONO (-8710 5435);
FORCEPROP 0 LASTPIN (-8700 5375) $PN B51
J 2
(-8710 5385);
DISPLAY 0.489362 (-8710 5385);
PAINT MONO (-8710 5385);
FORCEPROP 0 LASTPIN (-8700 5325) $PN B53
J 2
(-8710 5335);
DISPLAY 0.489362 (-8710 5335);
PAINT MONO (-8710 5335);
FORCEPROP 0 LASTPIN (-8700 5275) $PN B54
J 2
(-8710 5285);
DISPLAY 0.489362 (-8710 5285);
PAINT MONO (-8710 5285);
FORCEPROP 0 LASTPIN (-8700 5225) $PN B56
J 2
(-8710 5235);
DISPLAY 0.489362 (-8710 5235);
PAINT MONO (-8710 5235);
FORCEPROP 0 LASTPIN (-8700 5175) $PN B57
J 2
(-8710 5185);
DISPLAY 0.489362 (-8710 5185);
PAINT MONO (-8710 5185);
FORCEPROP 0 LASTPIN (-8700 5125) $PN C20
J 2
(-8710 5135);
DISPLAY 0.489362 (-8710 5135);
PAINT MONO (-8710 5135);
FORCEPROP 0 LASTPIN (-8700 5075) $PN D55
J 2
(-8710 5085);
DISPLAY 0.489362 (-8710 5085);
PAINT MONO (-8710 5085);
FORCEPROP 0 LASTPIN (-8700 5025) $PN D56
J 2
(-8710 5035);
DISPLAY 0.489362 (-8710 5035);
PAINT MONO (-8710 5035);
FORCEPROP 0 LASTPIN (-8700 4975) $PN E22
J 2
(-8710 4985);
DISPLAY 0.489362 (-8710 4985);
PAINT MONO (-8710 4985);
FORCEPROP 0 LASTPIN (-8700 4925) $PN E25
J 2
(-8710 4935);
DISPLAY 0.489362 (-8710 4935);
PAINT MONO (-8710 4935);
FORCEPROP 0 LASTPIN (-8700 4875) $PN E28
J 2
(-8710 4885);
DISPLAY 0.489362 (-8710 4885);
PAINT MONO (-8710 4885);
FORCEPROP 0 LASTPIN (-8700 4825) $PN E31
J 2
(-8710 4835);
DISPLAY 0.489362 (-8710 4835);
PAINT MONO (-8710 4835);
FORCEPROP 0 LASTPIN (-8700 4775) $PN E34
J 2
(-8710 4785);
DISPLAY 0.489362 (-8710 4785);
PAINT MONO (-8710 4785);
FORCEPROP 0 LASTPIN (-8700 4725) $PN E35
J 2
(-8710 4735);
DISPLAY 0.489362 (-8710 4735);
PAINT MONO (-8710 4735);
FORCEPROP 0 LASTPIN (-8700 4675) $PN E42
J 2
(-8710 4685);
DISPLAY 0.489362 (-8710 4685);
PAINT MONO (-8710 4685);
FORCEPROP 0 LASTPIN (-8700 4625) $PN E45
J 2
(-8710 4635);
DISPLAY 0.489362 (-8710 4635);
PAINT MONO (-8710 4635);
FORCEPROP 0 LASTPIN (-8700 4575) $PN E48
J 2
(-8710 4585);
DISPLAY 0.489362 (-8710 4585);
PAINT MONO (-8710 4585);
FORCEPROP 0 LASTPIN (-8700 4525) $PN E51
J 2
(-8710 4535);
DISPLAY 0.489362 (-8710 4535);
PAINT MONO (-8710 4535);
FORCEPROP 0 LASTPIN (-8700 4475) $PN E54
J 2
(-8710 4485);
DISPLAY 0.489362 (-8710 4485);
PAINT MONO (-8710 4485);
FORCEPROP 0 LASTPIN (-8700 4425) $PN F22
J 2
(-8710 4435);
DISPLAY 0.489362 (-8710 4435);
PAINT MONO (-8710 4435);
FORCEPROP 0 LASTPIN (-8700 4375) $PN F25
J 2
(-8710 4385);
DISPLAY 0.489362 (-8710 4385);
PAINT MONO (-8710 4385);
FORCEPROP 0 LASTPIN (-8700 4325) $PN F28
J 2
(-8710 4335);
DISPLAY 0.489362 (-8710 4335);
PAINT MONO (-8710 4335);
FORCEPROP 0 LASTPIN (-8700 4275) $PN F31
J 2
(-8710 4285);
DISPLAY 0.489362 (-8710 4285);
PAINT MONO (-8710 4285);
FORCEPROP 0 LASTPIN (-8700 4225) $PN F34
J 2
(-8710 4235);
DISPLAY 0.489362 (-8710 4235);
PAINT MONO (-8710 4235);
FORCEPROP 0 LASTPIN (-8700 4175) $PN F42
J 2
(-8710 4185);
DISPLAY 0.489362 (-8710 4185);
PAINT MONO (-8710 4185);
FORCEPROP 0 LASTPIN (-8700 4125) $PN F45
J 2
(-8710 4135);
DISPLAY 0.489362 (-8710 4135);
PAINT MONO (-8710 4135);
FORCEPROP 0 LASTPIN (-8700 4075) $PN F48
J 2
(-8710 4085);
DISPLAY 0.489362 (-8710 4085);
PAINT MONO (-8710 4085);
FORCEPROP 0 LASTPIN (-8700 4025) $PN F51
J 2
(-8710 4035);
DISPLAY 0.489362 (-8710 4035);
PAINT MONO (-8710 4035);
FORCEPROP 0 LASTPIN (-8700 3975) $PN F54
J 2
(-8710 3985);
DISPLAY 0.489362 (-8710 3985);
PAINT MONO (-8710 3985);
FORCEPROP 0 LASTPIN (-8700 3925) $PN G35
J 2
(-8710 3935);
DISPLAY 0.489362 (-8710 3935);
PAINT MONO (-8710 3935);
FORCEPROP 0 LASTPIN (-8700 3875) $PN G36
J 2
(-8710 3885);
DISPLAY 0.489362 (-8710 3885);
PAINT MONO (-8710 3885);
FORCEPROP 0 LASTPIN (-8700 3825) $PN G40
J 2
(-8710 3835);
DISPLAY 0.489362 (-8710 3835);
PAINT MONO (-8710 3835);
FORCEPROP 0 LASTPIN (-8700 3775) $PN G41
J 2
(-8710 3785);
DISPLAY 0.489362 (-8710 3785);
PAINT MONO (-8710 3785);
FORCEPROP 0 LASTPIN (-8700 3725) $PN H23
J 2
(-8710 3735);
DISPLAY 0.489362 (-8710 3735);
PAINT MONO (-8710 3735);
FORCEPROP 0 LASTPIN (-8700 3675) $PN H24
J 2
(-8710 3685);
DISPLAY 0.489362 (-8710 3685);
PAINT MONO (-8710 3685);
FORCEPROP 0 LASTPIN (-8700 3625) $PN H26
J 2
(-8710 3635);
DISPLAY 0.489362 (-8710 3635);
PAINT MONO (-8710 3635);
FORCEPROP 0 LASTPIN (-8700 3575) $PN H27
J 2
(-8710 3585);
DISPLAY 0.489362 (-8710 3585);
PAINT MONO (-8710 3585);
FORCEPROP 0 LASTPIN (-8700 3525) $PN H29
J 2
(-8710 3535);
DISPLAY 0.489362 (-8710 3535);
PAINT MONO (-8710 3535);
FORCEPROP 0 LASTPIN (-8700 3475) $PN H30
J 2
(-8710 3485);
DISPLAY 0.489362 (-8710 3485);
PAINT MONO (-8710 3485);
FORCEPROP 0 LASTPIN (-8700 3425) $PN H32
J 2
(-8710 3435);
DISPLAY 0.489362 (-8710 3435);
PAINT MONO (-8710 3435);
FORCEPROP 0 LASTPIN (-8700 3375) $PN H33
J 2
(-8710 3385);
DISPLAY 0.489362 (-8710 3385);
PAINT MONO (-8710 3385);
FORCEPROP 0 LASTPIN (-8700 3325) $PN H43
J 2
(-8710 3335);
DISPLAY 0.489362 (-8710 3335);
PAINT MONO (-8710 3335);
FORCEPROP 0 LASTPIN (-8700 3275) $PN H44
J 2
(-8710 3285);
DISPLAY 0.489362 (-8710 3285);
PAINT MONO (-8710 3285);
FORCEPROP 0 LASTPIN (-8700 3225) $PN H46
J 2
(-8710 3235);
DISPLAY 0.489362 (-8710 3235);
PAINT MONO (-8710 3235);
FORCEPROP 0 LASTPIN (-8700 3175) $PN H47
J 2
(-8710 3185);
DISPLAY 0.489362 (-8710 3185);
PAINT MONO (-8710 3185);
FORCEPROP 0 LASTPIN (-8700 3125) $PN H49
J 2
(-8710 3135);
DISPLAY 0.489362 (-8710 3135);
PAINT MONO (-8710 3135);
FORCEPROP 0 LASTPIN (-8700 3075) $PN H50
J 2
(-8710 3085);
DISPLAY 0.489362 (-8710 3085);
PAINT MONO (-8710 3085);
FORCEPROP 0 LASTPIN (-8700 3025) $PN H52
J 2
(-8710 3035);
DISPLAY 0.489362 (-8710 3035);
PAINT MONO (-8710 3035);
FORCEPROP 0 LASTPIN (-8700 2975) $PN H53
J 2
(-8710 2985);
DISPLAY 0.489362 (-8710 2985);
PAINT MONO (-8710 2985);
FORCEPROP 0 LASTPIN (-8700 2925) $PN J35
J 2
(-8710 2935);
DISPLAY 0.489362 (-8710 2935);
PAINT MONO (-8710 2935);
FORCEPROP 0 LASTPIN (-8700 2875) $PN J36
J 2
(-8710 2885);
DISPLAY 0.489362 (-8710 2885);
PAINT MONO (-8710 2885);
FORCEPROP 0 LASTPIN (-8700 2825) $PN J40
J 2
(-8710 2835);
DISPLAY 0.489362 (-8710 2835);
PAINT MONO (-8710 2835);
FORCEPROP 0 LASTPIN (-8700 2775) $PN J41
J 2
(-8710 2785);
DISPLAY 0.489362 (-8710 2785);
PAINT MONO (-8710 2785);
FORCEPROP 0 LASTPIN (-8700 2725) $PN M23
J 2
(-8710 2735);
DISPLAY 0.489362 (-8710 2735);
PAINT MONO (-8710 2735);
FORCEPROP 0 LASTPIN (-8700 2675) $PN M24
J 2
(-8710 2685);
DISPLAY 0.489362 (-8710 2685);
PAINT MONO (-8710 2685);
FORCEPROP 0 LASTPIN (-8700 2625) $PN M26
J 2
(-8710 2635);
DISPLAY 0.489362 (-8710 2635);
PAINT MONO (-8710 2635);
FORCEPROP 0 LASTPIN (-8700 2575) $PN M27
J 2
(-8710 2585);
DISPLAY 0.489362 (-8710 2585);
PAINT MONO (-8710 2585);
FORCEPROP 0 LASTPIN (-8700 2525) $PN M29
J 2
(-8710 2535);
DISPLAY 0.489362 (-8710 2535);
PAINT MONO (-8710 2535);
FORCEPROP 0 LASTPIN (-8700 2475) $PN M30
J 2
(-8710 2485);
DISPLAY 0.489362 (-8710 2485);
PAINT MONO (-8710 2485);
FORCEPROP 0 LASTPIN (-8700 2425) $PN M32
J 2
(-8710 2435);
DISPLAY 0.489362 (-8710 2435);
PAINT MONO (-8710 2435);
FORCEPROP 0 LASTPIN (-8700 2375) $PN M33
J 2
(-8710 2385);
DISPLAY 0.489362 (-8710 2385);
PAINT MONO (-8710 2385);
FORCEPROP 0 LASTPIN (-8700 2325) $PN M43
J 2
(-8710 2335);
DISPLAY 0.489362 (-8710 2335);
PAINT MONO (-8710 2335);
FORCEPROP 0 LASTPIN (-8700 2275) $PN M44
J 2
(-8710 2285);
DISPLAY 0.489362 (-8710 2285);
PAINT MONO (-8710 2285);
FORCEPROP 0 LASTPIN (-8700 2225) $PN M46
J 2
(-8710 2235);
DISPLAY 0.489362 (-8710 2235);
PAINT MONO (-8710 2235);
FORCEPROP 0 LASTPIN (-8700 2175) $PN M47
J 2
(-8710 2185);
DISPLAY 0.489362 (-8710 2185);
PAINT MONO (-8710 2185);
FORCEPROP 0 LASTPIN (-8700 2125) $PN M49
J 2
(-8710 2135);
DISPLAY 0.489362 (-8710 2135);
PAINT MONO (-8710 2135);
FORCEPROP 0 LASTPIN (-8700 2075) $PN M50
J 2
(-8710 2085);
DISPLAY 0.489362 (-8710 2085);
PAINT MONO (-8710 2085);
FORCEPROP 0 LASTPIN (-8700 2025) $PN M52
J 2
(-8710 2035);
DISPLAY 0.489362 (-8710 2035);
PAINT MONO (-8710 2035);
FORCEPROP 0 LASTPIN (-8700 1975) $PN M53
J 2
(-8710 1985);
DISPLAY 0.489362 (-8710 1985);
PAINT MONO (-8710 1985);
FORCEPROP 0 LASTPIN (-8700 1925) $PN N35
J 2
(-8710 1935);
DISPLAY 0.489362 (-8710 1935);
PAINT MONO (-8710 1935);
FORCEPROP 0 LASTPIN (-8700 1875) $PN N36
J 2
(-8710 1885);
DISPLAY 0.489362 (-8710 1885);
PAINT MONO (-8710 1885);
FORCEPROP 0 LASTPIN (-8700 1825) $PN N40
J 2
(-8710 1835);
DISPLAY 0.489362 (-8710 1835);
PAINT MONO (-8710 1835);
FORCEPROP 0 LASTPIN (-8700 1775) $PN N41
J 2
(-8710 1785);
DISPLAY 0.489362 (-8710 1785);
PAINT MONO (-8710 1785);
FORCEPROP 0 LASTPIN (-8700 1725) $PN T23
J 2
(-8710 1735);
DISPLAY 0.489362 (-8710 1735);
PAINT MONO (-8710 1735);
FORCEPROP 0 LASTPIN (-8700 1675) $PN T24
J 2
(-8710 1685);
DISPLAY 0.489362 (-8710 1685);
PAINT MONO (-8710 1685);
FORCEPROP 0 LASTPIN (-8700 1625) $PN T26
J 2
(-8710 1635);
DISPLAY 0.489362 (-8710 1635);
PAINT MONO (-8710 1635);
FORCEPROP 0 LASTPIN (-8700 1575) $PN T27
J 2
(-8710 1585);
DISPLAY 0.489362 (-8710 1585);
PAINT MONO (-8710 1585);
FORCEPROP 0 LASTPIN (-8700 1525) $PN T29
J 2
(-8710 1535);
DISPLAY 0.489362 (-8710 1535);
PAINT MONO (-8710 1535);
FORCEPROP 0 LASTPIN (-8700 1475) $PN T30
J 2
(-8710 1485);
DISPLAY 0.489362 (-8710 1485);
PAINT MONO (-8710 1485);
FORCEPROP 0 LASTPIN (-8700 1425) $PN T32
J 2
(-8710 1435);
DISPLAY 0.489362 (-8710 1435);
PAINT MONO (-8710 1435);
FORCEPROP 0 LASTPIN (-8700 1375) $PN T33
J 2
(-8710 1385);
DISPLAY 0.489362 (-8710 1385);
PAINT MONO (-8710 1385);
FORCEPROP 0 LASTPIN (-8700 1325) $PN T43
J 2
(-8710 1335);
DISPLAY 0.489362 (-8710 1335);
PAINT MONO (-8710 1335);
FORCEPROP 0 LASTPIN (-8700 1275) $PN T44
J 2
(-8710 1285);
DISPLAY 0.489362 (-8710 1285);
PAINT MONO (-8710 1285);
FORCEPROP 0 LASTPIN (-8700 1225) $PN T46
J 2
(-8710 1235);
DISPLAY 0.489362 (-8710 1235);
PAINT MONO (-8710 1235);
FORCEPROP 0 LASTPIN (-8700 1175) $PN T47
J 2
(-8710 1185);
DISPLAY 0.489362 (-8710 1185);
PAINT MONO (-8710 1185);
FORCEPROP 0 LASTPIN (-8700 1125) $PN T49
J 2
(-8710 1135);
DISPLAY 0.489362 (-8710 1135);
PAINT MONO (-8710 1135);
FORCEPROP 0 LASTPIN (-8700 1075) $PN T50
J 2
(-8710 1085);
DISPLAY 0.489362 (-8710 1085);
PAINT MONO (-8710 1085);
FORCEPROP 0 LASTPIN (-8700 1025) $PN T52
J 2
(-8710 1035);
DISPLAY 0.489362 (-8710 1035);
PAINT MONO (-8710 1035);
FORCEPROP 0 LASTPIN (-8700 975) $PN T53
J 2
(-8710 985);
DISPLAY 0.489362 (-8710 985);
PAINT MONO (-8710 985);
FORCEPROP 0 LASTPIN (-8700 925) $PN U35
J 2
(-8710 935);
DISPLAY 0.489362 (-8710 935);
PAINT MONO (-8710 935);
FORCEPROP 0 LASTPIN (-8700 875) $PN U36
J 2
(-8710 885);
DISPLAY 0.489362 (-8710 885);
PAINT MONO (-8710 885);
FORCEPROP 0 LASTPIN (-8700 825) $PN U40
J 2
(-8710 835);
DISPLAY 0.489362 (-8710 835);
PAINT MONO (-8710 835);
FORCEPROP 0 LASTPIN (-8700 775) $PN U41
J 2
(-8710 785);
DISPLAY 0.489362 (-8710 785);
PAINT MONO (-8710 785);
FORCEPROP 0 LASTPIN (-8700 725) $PN W29
J 2
(-8710 735);
DISPLAY 0.489362 (-8710 735);
PAINT MONO (-8710 735);
FORCEPROP 0 LASTPIN (-8700 675) $PN W30
J 2
(-8710 685);
DISPLAY 0.489362 (-8710 685);
PAINT MONO (-8710 685);
FORCEPROP 0 LASTPIN (-8700 625) $PN W32
J 2
(-8710 635);
DISPLAY 0.489362 (-8710 635);
PAINT MONO (-8710 635);
FORCEPROP 0 LASTPIN (-8700 575) $PN W33
J 2
(-8710 585);
DISPLAY 0.489362 (-8710 585);
PAINT MONO (-8710 585);
FORCEPROP 0 LASTPIN (-7400 6325) $PN W43
J 0
(-7390 6335);
DISPLAY 0.489362 (-7390 6335);
PAINT MONO (-7390 6335);
FORCEPROP 0 LASTPIN (-7400 6275) $PN W44
J 0
(-7390 6285);
DISPLAY 0.489362 (-7390 6285);
PAINT MONO (-7390 6285);
FORCEPROP 0 LASTPIN (-7400 6225) $PN W46
J 0
(-7390 6235);
DISPLAY 0.489362 (-7390 6235);
PAINT MONO (-7390 6235);
FORCEPROP 0 LASTPIN (-7400 6175) $PN W47
J 0
(-7390 6185);
DISPLAY 0.489362 (-7390 6185);
PAINT MONO (-7390 6185);
FORCEPROP 0 LASTPIN (-7400 6125) $PN Y35
J 0
(-7390 6135);
DISPLAY 0.489362 (-7390 6135);
PAINT MONO (-7390 6135);
FORCEPROP 0 LASTPIN (-7400 6075) $PN Y36
J 0
(-7390 6085);
DISPLAY 0.489362 (-7390 6085);
PAINT MONO (-7390 6085);
FORCEPROP 0 LASTPIN (-7400 6025) $PN Y40
J 0
(-7390 6035);
DISPLAY 0.489362 (-7390 6035);
PAINT MONO (-7390 6035);
FORCEPROP 0 LASTPIN (-7400 5975) $PN Y41
J 0
(-7390 5985);
DISPLAY 0.489362 (-7390 5985);
PAINT MONO (-7390 5985);
FORCEPROP 2 LAST PART_TYPE SMLF
J 0
(-8550 6700);
DISPLAY 1.021277 (-8550 6700);
FORCEPROP 1 LAST MATERIAL IO
J 0
(-8545 6495);
DISPLAY 0.489362 (-8545 6495);
PAINT SKYBLUE (-8545 6495);
FORCEPROP 2 LAST VALUE SOCKET6096_13568-001
J 0
(-8550 6550);
DISPLAY 0.489362 (-8550 6550);
PAINT SKYBLUE (-8550 6550);
FORCEPROP 2 LAST CDS_LIB pure_quanta
J 0
(-8050 3325);
DISPLAY INVISIBLE (-8050 3325);
FORCEPROP 1 LAST CDS_LMAN_SYM_OUTLINE -500,3150,500,-3150
J 0
(-8050 3325);
DISPLAY 0.468085 (-8050 3325);
PAINT GREEN (-8050 3325);
DISPLAY INVISIBLE (-8050 3325);
FORCEPROP 1 LAST NEEDS_NO_SIZE TRUE
J 0
(-8050 3325);
DISPLAY 0.723404 (-8050 3325);
PAINT GREEN (-8050 3325);
DISPLAY INVISIBLE (-8050 3325);
FORCEPROP 1 LAST PATH I42
J 0
(-8050 3325);
DISPLAY 0.723404 (-8050 3325);
PAINT GREEN (-8050 3325);
DISPLAY INVISIBLE (-8050 3325);
FORCEPROP 1 LAST PART_NUMBER DGA^6000030
J 0
(-8550 6650);
DISPLAY 0.489362 (-8550 6650);
PAINT SKYBLUE (-8550 6650);
DISPLAY INVISIBLE (-8550 6650);
FORCEADD VCC_CORE..1
(-7250 6575);
FORCEPROP 3 LASTPIN (-7250 6525) SIG_NAME PVDDCR_CPU0_P0\g
J 0
(-7240 6535);
DISPLAY 0.659574 (-7240 6535);
PAINT MONO (-7240 6535);
DISPLAY INVISIBLE (-7240 6535);
FORCEPROP 1 LAST HDL_POWER PVDDCR_CPU0_P0
J 1
(-7250 6625);
DISPLAY 0.489362 (-7250 6625);
PAINT GREEN (-7250 6625);
FORCEPROP 2 LAST CDS_LIB pure_quanta_power
J 0
(-7250 6575);
DISPLAY INVISIBLE (-7250 6575);
FORCEPROP 1 LAST PATH I43
J 0
(-7200 6600);
DISPLAY 0.872340 (-7200 6600);
PAINT AQUA (-7200 6600);
DISPLAY INVISIBLE (-7200 6600);
FORCEADD GENOA_SP5..25
(-6075 3350);
FORCEPROP 1 LAST LOCATION U25
J 0
(-6575 6650);
DISPLAY 0.489362 (-6575 6650);
PAINT SKYBLUE (-6575 6650);
FORCEPROP 0 LAST $SEC 25
J 0
(-6550 6900);
DISPLAY 0.680851 (-6550 6900);
PAINT MONO (-6550 6900);
DISPLAY INVISIBLE (-6550 6900);
FORCEPROP 0 LAST CDS_SEC 25
J 0
(-6950 6575);
DISPLAY 1.021277 (-6950 6575);
DISPLAY INVISIBLE (-6950 6575);
FORCEPROP 0 LASTPIN (-5425 500) $PN BN27
J 0
(-5415 510);
DISPLAY 0.489362 (-5415 510);
PAINT MONO (-5415 510);
FORCEPROP 0 LASTPIN (-6725 6100) $PN BN31
J 2
(-6735 6110);
DISPLAY 0.489362 (-6735 6110);
PAINT MONO (-6735 6110);
FORCEPROP 0 LASTPIN (-5425 450) $PN BN35
J 0
(-5415 460);
DISPLAY 0.489362 (-5415 460);
PAINT MONO (-5415 460);
FORCEPROP 0 LASTPIN (-6725 6050) $PN BN42
J 2
(-6735 6060);
DISPLAY 0.489362 (-6735 6060);
PAINT MONO (-6735 6060);
FORCEPROP 0 LASTPIN (-5425 400) $PN BN46
J 0
(-5415 410);
DISPLAY 0.489362 (-5415 410);
PAINT MONO (-5415 410);
FORCEPROP 0 LASTPIN (-6725 6000) $PN BN50
J 2
(-6735 6010);
DISPLAY 0.489362 (-6735 6010);
PAINT MONO (-6735 6010);
FORCEPROP 0 LASTPIN (-5425 350) $PN BP24
J 0
(-5415 360);
DISPLAY 0.489362 (-5415 360);
PAINT MONO (-5415 360);
FORCEPROP 0 LASTPIN (-6725 5950) $PN BP26
J 2
(-6735 5960);
DISPLAY 0.489362 (-6735 5960);
PAINT MONO (-6735 5960);
FORCEPROP 0 LASTPIN (-5425 300) $PN BP28
J 0
(-5415 310);
DISPLAY 0.489362 (-5415 310);
PAINT MONO (-5415 310);
FORCEPROP 0 LASTPIN (-6725 5900) $PN BP30
J 2
(-6735 5910);
DISPLAY 0.489362 (-6735 5910);
PAINT MONO (-6735 5910);
FORCEPROP 0 LASTPIN (-5425 250) $PN BP32
J 0
(-5415 260);
DISPLAY 0.489362 (-5415 260);
PAINT MONO (-5415 260);
FORCEPROP 0 LASTPIN (-6725 5850) $PN BP34
J 2
(-6735 5860);
DISPLAY 0.489362 (-6735 5860);
PAINT MONO (-6735 5860);
FORCEPROP 0 LASTPIN (-6725 5800) $PN BP36
J 2
(-6735 5810);
DISPLAY 0.489362 (-6735 5810);
PAINT MONO (-6735 5810);
FORCEPROP 0 LASTPIN (-6725 5750) $PN BP39
J 2
(-6735 5760);
DISPLAY 0.489362 (-6735 5760);
PAINT MONO (-6735 5760);
FORCEPROP 0 LASTPIN (-6725 5700) $PN BP41
J 2
(-6735 5710);
DISPLAY 0.489362 (-6735 5710);
PAINT MONO (-6735 5710);
FORCEPROP 0 LASTPIN (-6725 5650) $PN BP43
J 2
(-6735 5660);
DISPLAY 0.489362 (-6735 5660);
PAINT MONO (-6735 5660);
FORCEPROP 0 LASTPIN (-6725 5600) $PN BP45
J 2
(-6735 5610);
DISPLAY 0.489362 (-6735 5610);
PAINT MONO (-6735 5610);
FORCEPROP 0 LASTPIN (-6725 5550) $PN BP47
J 2
(-6735 5560);
DISPLAY 0.489362 (-6735 5560);
PAINT MONO (-6735 5560);
FORCEPROP 0 LASTPIN (-6725 5500) $PN BP49
J 2
(-6735 5510);
DISPLAY 0.489362 (-6735 5510);
PAINT MONO (-6735 5510);
FORCEPROP 0 LASTPIN (-6725 5450) $PN BR23
J 2
(-6735 5460);
DISPLAY 0.489362 (-6735 5460);
PAINT MONO (-6735 5460);
FORCEPROP 0 LASTPIN (-6725 5400) $PN BR25
J 2
(-6735 5410);
DISPLAY 0.489362 (-6735 5410);
PAINT MONO (-6735 5410);
FORCEPROP 0 LASTPIN (-6725 5350) $PN BR27
J 2
(-6735 5360);
DISPLAY 0.489362 (-6735 5360);
PAINT MONO (-6735 5360);
FORCEPROP 0 LASTPIN (-6725 5300) $PN BR29
J 2
(-6735 5310);
DISPLAY 0.489362 (-6735 5310);
PAINT MONO (-6735 5310);
FORCEPROP 0 LASTPIN (-6725 5250) $PN BR31
J 2
(-6735 5260);
DISPLAY 0.489362 (-6735 5260);
PAINT MONO (-6735 5260);
FORCEPROP 0 LASTPIN (-6725 5200) $PN BR33
J 2
(-6735 5210);
DISPLAY 0.489362 (-6735 5210);
PAINT MONO (-6735 5210);
FORCEPROP 0 LASTPIN (-6725 5150) $PN BR35
J 2
(-6735 5160);
DISPLAY 0.489362 (-6735 5160);
PAINT MONO (-6735 5160);
FORCEPROP 0 LASTPIN (-6725 5100) $PN BR40
J 2
(-6735 5110);
DISPLAY 0.489362 (-6735 5110);
PAINT MONO (-6735 5110);
FORCEPROP 0 LASTPIN (-6725 5050) $PN BR42
J 2
(-6735 5060);
DISPLAY 0.489362 (-6735 5060);
PAINT MONO (-6735 5060);
FORCEPROP 0 LASTPIN (-6725 5000) $PN BR44
J 2
(-6735 5010);
DISPLAY 0.489362 (-6735 5010);
PAINT MONO (-6735 5010);
FORCEPROP 0 LASTPIN (-6725 4950) $PN BR46
J 2
(-6735 4960);
DISPLAY 0.489362 (-6735 4960);
PAINT MONO (-6735 4960);
FORCEPROP 0 LASTPIN (-6725 4900) $PN BR48
J 2
(-6735 4910);
DISPLAY 0.489362 (-6735 4910);
PAINT MONO (-6735 4910);
FORCEPROP 0 LASTPIN (-6725 4850) $PN BR50
J 2
(-6735 4860);
DISPLAY 0.489362 (-6735 4860);
PAINT MONO (-6735 4860);
FORCEPROP 0 LASTPIN (-6725 4800) $PN BR52
J 2
(-6735 4810);
DISPLAY 0.489362 (-6735 4810);
PAINT MONO (-6735 4810);
FORCEPROP 0 LASTPIN (-6725 4750) $PN BT23
J 2
(-6735 4760);
DISPLAY 0.489362 (-6735 4760);
PAINT MONO (-6735 4760);
FORCEPROP 0 LASTPIN (-6725 4700) $PN BT24
J 2
(-6735 4710);
DISPLAY 0.489362 (-6735 4710);
PAINT MONO (-6735 4710);
FORCEPROP 0 LASTPIN (-6725 4650) $PN BT26
J 2
(-6735 4660);
DISPLAY 0.489362 (-6735 4660);
PAINT MONO (-6735 4660);
FORCEPROP 0 LASTPIN (-6725 4600) $PN BT27
J 2
(-6735 4610);
DISPLAY 0.489362 (-6735 4610);
PAINT MONO (-6735 4610);
FORCEPROP 0 LASTPIN (-6725 4550) $PN BT29
J 2
(-6735 4560);
DISPLAY 0.489362 (-6735 4560);
PAINT MONO (-6735 4560);
FORCEPROP 0 LASTPIN (-6725 4500) $PN BT30
J 2
(-6735 4510);
DISPLAY 0.489362 (-6735 4510);
PAINT MONO (-6735 4510);
FORCEPROP 0 LASTPIN (-6725 4450) $PN BT32
J 2
(-6735 4460);
DISPLAY 0.489362 (-6735 4460);
PAINT MONO (-6735 4460);
FORCEPROP 0 LASTPIN (-6725 4400) $PN BT33
J 2
(-6735 4410);
DISPLAY 0.489362 (-6735 4410);
PAINT MONO (-6735 4410);
FORCEPROP 0 LASTPIN (-6725 4350) $PN BT43
J 2
(-6735 4360);
DISPLAY 0.489362 (-6735 4360);
PAINT MONO (-6735 4360);
FORCEPROP 0 LASTPIN (-6725 4300) $PN BT44
J 2
(-6735 4310);
DISPLAY 0.489362 (-6735 4310);
PAINT MONO (-6735 4310);
FORCEPROP 0 LASTPIN (-6725 4250) $PN BT46
J 2
(-6735 4260);
DISPLAY 0.489362 (-6735 4260);
PAINT MONO (-6735 4260);
FORCEPROP 0 LASTPIN (-6725 4200) $PN BT47
J 2
(-6735 4210);
DISPLAY 0.489362 (-6735 4210);
PAINT MONO (-6735 4210);
FORCEPROP 0 LASTPIN (-6725 4150) $PN BT49
J 2
(-6735 4160);
DISPLAY 0.489362 (-6735 4160);
PAINT MONO (-6735 4160);
FORCEPROP 0 LASTPIN (-6725 4100) $PN BT50
J 2
(-6735 4110);
DISPLAY 0.489362 (-6735 4110);
PAINT MONO (-6735 4110);
FORCEPROP 0 LASTPIN (-6725 4050) $PN BT52
J 2
(-6735 4060);
DISPLAY 0.489362 (-6735 4060);
PAINT MONO (-6735 4060);
FORCEPROP 0 LASTPIN (-6725 4000) $PN BT53
J 2
(-6735 4010);
DISPLAY 0.489362 (-6735 4010);
PAINT MONO (-6735 4010);
FORCEPROP 0 LASTPIN (-6725 3950) $PN BW35
J 2
(-6735 3960);
DISPLAY 0.489362 (-6735 3960);
PAINT MONO (-6735 3960);
FORCEPROP 0 LASTPIN (-6725 3900) $PN BW36
J 2
(-6735 3910);
DISPLAY 0.489362 (-6735 3910);
PAINT MONO (-6735 3910);
FORCEPROP 0 LASTPIN (-6725 3850) $PN BW40
J 2
(-6735 3860);
DISPLAY 0.489362 (-6735 3860);
PAINT MONO (-6735 3860);
FORCEPROP 0 LASTPIN (-6725 3800) $PN BW41
J 2
(-6735 3810);
DISPLAY 0.489362 (-6735 3810);
PAINT MONO (-6735 3810);
FORCEPROP 0 LASTPIN (-6725 3750) $PN BY23
J 2
(-6735 3760);
DISPLAY 0.489362 (-6735 3760);
PAINT MONO (-6735 3760);
FORCEPROP 0 LASTPIN (-6725 3700) $PN BY24
J 2
(-6735 3710);
DISPLAY 0.489362 (-6735 3710);
PAINT MONO (-6735 3710);
FORCEPROP 0 LASTPIN (-6725 3650) $PN BY26
J 2
(-6735 3660);
DISPLAY 0.489362 (-6735 3660);
PAINT MONO (-6735 3660);
FORCEPROP 0 LASTPIN (-6725 3600) $PN BY27
J 2
(-6735 3610);
DISPLAY 0.489362 (-6735 3610);
PAINT MONO (-6735 3610);
FORCEPROP 0 LASTPIN (-6725 3550) $PN BY29
J 2
(-6735 3560);
DISPLAY 0.489362 (-6735 3560);
PAINT MONO (-6735 3560);
FORCEPROP 0 LASTPIN (-6725 3500) $PN BY30
J 2
(-6735 3510);
DISPLAY 0.489362 (-6735 3510);
PAINT MONO (-6735 3510);
FORCEPROP 0 LASTPIN (-6725 3450) $PN BY32
J 2
(-6735 3460);
DISPLAY 0.489362 (-6735 3460);
PAINT MONO (-6735 3460);
FORCEPROP 0 LASTPIN (-6725 3400) $PN BY33
J 2
(-6735 3410);
DISPLAY 0.489362 (-6735 3410);
PAINT MONO (-6735 3410);
FORCEPROP 0 LASTPIN (-6725 3350) $PN BY43
J 2
(-6735 3360);
DISPLAY 0.489362 (-6735 3360);
PAINT MONO (-6735 3360);
FORCEPROP 0 LASTPIN (-6725 3300) $PN BY44
J 2
(-6735 3310);
DISPLAY 0.489362 (-6735 3310);
PAINT MONO (-6735 3310);
FORCEPROP 0 LASTPIN (-6725 3250) $PN BY46
J 2
(-6735 3260);
DISPLAY 0.489362 (-6735 3260);
PAINT MONO (-6735 3260);
FORCEPROP 0 LASTPIN (-6725 3200) $PN BY47
J 2
(-6735 3210);
DISPLAY 0.489362 (-6735 3210);
PAINT MONO (-6735 3210);
FORCEPROP 0 LASTPIN (-6725 3150) $PN BY49
J 2
(-6735 3160);
DISPLAY 0.489362 (-6735 3160);
PAINT MONO (-6735 3160);
FORCEPROP 0 LASTPIN (-6725 3100) $PN BY50
J 2
(-6735 3110);
DISPLAY 0.489362 (-6735 3110);
PAINT MONO (-6735 3110);
FORCEPROP 0 LASTPIN (-6725 3050) $PN BY52
J 2
(-6735 3060);
DISPLAY 0.489362 (-6735 3060);
PAINT MONO (-6735 3060);
FORCEPROP 0 LASTPIN (-6725 3000) $PN BY53
J 2
(-6735 3010);
DISPLAY 0.489362 (-6735 3010);
PAINT MONO (-6735 3010);
FORCEPROP 0 LASTPIN (-6725 2950) $PN CC35
J 2
(-6735 2960);
DISPLAY 0.489362 (-6735 2960);
PAINT MONO (-6735 2960);
FORCEPROP 0 LASTPIN (-6725 2900) $PN CC36
J 2
(-6735 2910);
DISPLAY 0.489362 (-6735 2910);
PAINT MONO (-6735 2910);
FORCEPROP 0 LASTPIN (-6725 2850) $PN CC40
J 2
(-6735 2860);
DISPLAY 0.489362 (-6735 2860);
PAINT MONO (-6735 2860);
FORCEPROP 0 LASTPIN (-6725 2800) $PN CC41
J 2
(-6735 2810);
DISPLAY 0.489362 (-6735 2810);
PAINT MONO (-6735 2810);
FORCEPROP 0 LASTPIN (-6725 2750) $PN CD23
J 2
(-6735 2760);
DISPLAY 0.489362 (-6735 2760);
PAINT MONO (-6735 2760);
FORCEPROP 0 LASTPIN (-6725 2700) $PN CD24
J 2
(-6735 2710);
DISPLAY 0.489362 (-6735 2710);
PAINT MONO (-6735 2710);
FORCEPROP 0 LASTPIN (-6725 2650) $PN CD26
J 2
(-6735 2660);
DISPLAY 0.489362 (-6735 2660);
PAINT MONO (-6735 2660);
FORCEPROP 0 LASTPIN (-6725 2600) $PN CD27
J 2
(-6735 2610);
DISPLAY 0.489362 (-6735 2610);
PAINT MONO (-6735 2610);
FORCEPROP 0 LASTPIN (-6725 2550) $PN CD29
J 2
(-6735 2560);
DISPLAY 0.489362 (-6735 2560);
PAINT MONO (-6735 2560);
FORCEPROP 0 LASTPIN (-6725 2500) $PN CD30
J 2
(-6735 2510);
DISPLAY 0.489362 (-6735 2510);
PAINT MONO (-6735 2510);
FORCEPROP 0 LASTPIN (-6725 2450) $PN CD32
J 2
(-6735 2460);
DISPLAY 0.489362 (-6735 2460);
PAINT MONO (-6735 2460);
FORCEPROP 0 LASTPIN (-6725 2400) $PN CD33
J 2
(-6735 2410);
DISPLAY 0.489362 (-6735 2410);
PAINT MONO (-6735 2410);
FORCEPROP 0 LASTPIN (-6725 2350) $PN CD43
J 2
(-6735 2360);
DISPLAY 0.489362 (-6735 2360);
PAINT MONO (-6735 2360);
FORCEPROP 0 LASTPIN (-6725 2300) $PN CD44
J 2
(-6735 2310);
DISPLAY 0.489362 (-6735 2310);
PAINT MONO (-6735 2310);
FORCEPROP 0 LASTPIN (-6725 2250) $PN CD46
J 2
(-6735 2260);
DISPLAY 0.489362 (-6735 2260);
PAINT MONO (-6735 2260);
FORCEPROP 0 LASTPIN (-6725 2200) $PN CD47
J 2
(-6735 2210);
DISPLAY 0.489362 (-6735 2210);
PAINT MONO (-6735 2210);
FORCEPROP 0 LASTPIN (-6725 2150) $PN CD49
J 2
(-6735 2160);
DISPLAY 0.489362 (-6735 2160);
PAINT MONO (-6735 2160);
FORCEPROP 0 LASTPIN (-6725 2100) $PN CD50
J 2
(-6735 2110);
DISPLAY 0.489362 (-6735 2110);
PAINT MONO (-6735 2110);
FORCEPROP 0 LASTPIN (-6725 2050) $PN CD52
J 2
(-6735 2060);
DISPLAY 0.489362 (-6735 2060);
PAINT MONO (-6735 2060);
FORCEPROP 0 LASTPIN (-6725 2000) $PN CD53
J 2
(-6735 2010);
DISPLAY 0.489362 (-6735 2010);
PAINT MONO (-6735 2010);
FORCEPROP 0 LASTPIN (-6725 1950) $PN CG35
J 2
(-6735 1960);
DISPLAY 0.489362 (-6735 1960);
PAINT MONO (-6735 1960);
FORCEPROP 0 LASTPIN (-6725 1900) $PN CG36
J 2
(-6735 1910);
DISPLAY 0.489362 (-6735 1910);
PAINT MONO (-6735 1910);
FORCEPROP 0 LASTPIN (-6725 1850) $PN CG40
J 2
(-6735 1860);
DISPLAY 0.489362 (-6735 1860);
PAINT MONO (-6735 1860);
FORCEPROP 0 LASTPIN (-6725 1800) $PN CG41
J 2
(-6735 1810);
DISPLAY 0.489362 (-6735 1810);
PAINT MONO (-6735 1810);
FORCEPROP 0 LASTPIN (-6725 1750) $PN CH23
J 2
(-6735 1760);
DISPLAY 0.489362 (-6735 1760);
PAINT MONO (-6735 1760);
FORCEPROP 0 LASTPIN (-6725 1700) $PN CH24
J 2
(-6735 1710);
DISPLAY 0.489362 (-6735 1710);
PAINT MONO (-6735 1710);
FORCEPROP 0 LASTPIN (-6725 1650) $PN CH26
J 2
(-6735 1660);
DISPLAY 0.489362 (-6735 1660);
PAINT MONO (-6735 1660);
FORCEPROP 0 LASTPIN (-6725 1600) $PN CH27
J 2
(-6735 1610);
DISPLAY 0.489362 (-6735 1610);
PAINT MONO (-6735 1610);
FORCEPROP 0 LASTPIN (-6725 1550) $PN CH29
J 2
(-6735 1560);
DISPLAY 0.489362 (-6735 1560);
PAINT MONO (-6735 1560);
FORCEPROP 0 LASTPIN (-6725 1500) $PN CH30
J 2
(-6735 1510);
DISPLAY 0.489362 (-6735 1510);
PAINT MONO (-6735 1510);
FORCEPROP 0 LASTPIN (-6725 1450) $PN CH32
J 2
(-6735 1460);
DISPLAY 0.489362 (-6735 1460);
PAINT MONO (-6735 1460);
FORCEPROP 0 LASTPIN (-6725 1400) $PN CH33
J 2
(-6735 1410);
DISPLAY 0.489362 (-6735 1410);
PAINT MONO (-6735 1410);
FORCEPROP 0 LASTPIN (-6725 1350) $PN CH43
J 2
(-6735 1360);
DISPLAY 0.489362 (-6735 1360);
PAINT MONO (-6735 1360);
FORCEPROP 0 LASTPIN (-6725 1300) $PN CH44
J 2
(-6735 1310);
DISPLAY 0.489362 (-6735 1310);
PAINT MONO (-6735 1310);
FORCEPROP 0 LASTPIN (-6725 1250) $PN CH46
J 2
(-6735 1260);
DISPLAY 0.489362 (-6735 1260);
PAINT MONO (-6735 1260);
FORCEPROP 0 LASTPIN (-6725 1200) $PN CH47
J 2
(-6735 1210);
DISPLAY 0.489362 (-6735 1210);
PAINT MONO (-6735 1210);
FORCEPROP 0 LASTPIN (-6725 1150) $PN CH49
J 2
(-6735 1160);
DISPLAY 0.489362 (-6735 1160);
PAINT MONO (-6735 1160);
FORCEPROP 0 LASTPIN (-6725 1100) $PN CH50
J 2
(-6735 1110);
DISPLAY 0.489362 (-6735 1110);
PAINT MONO (-6735 1110);
FORCEPROP 0 LASTPIN (-6725 1050) $PN CH52
J 2
(-6735 1060);
DISPLAY 0.489362 (-6735 1060);
PAINT MONO (-6735 1060);
FORCEPROP 0 LASTPIN (-6725 1000) $PN CH53
J 2
(-6735 1010);
DISPLAY 0.489362 (-6735 1010);
PAINT MONO (-6735 1010);
FORCEPROP 0 LASTPIN (-6725 950) $PN CK35
J 2
(-6735 960);
DISPLAY 0.489362 (-6735 960);
PAINT MONO (-6735 960);
FORCEPROP 0 LASTPIN (-6725 900) $PN CK36
J 2
(-6735 910);
DISPLAY 0.489362 (-6735 910);
PAINT MONO (-6735 910);
FORCEPROP 0 LASTPIN (-6725 850) $PN CK40
J 2
(-6735 860);
DISPLAY 0.489362 (-6735 860);
PAINT MONO (-6735 860);
FORCEPROP 0 LASTPIN (-6725 800) $PN CK41
J 2
(-6735 810);
DISPLAY 0.489362 (-6735 810);
PAINT MONO (-6735 810);
FORCEPROP 0 LASTPIN (-6725 750) $PN CL29
J 2
(-6735 760);
DISPLAY 0.489362 (-6735 760);
PAINT MONO (-6735 760);
FORCEPROP 0 LASTPIN (-6725 700) $PN CL30
J 2
(-6735 710);
DISPLAY 0.489362 (-6735 710);
PAINT MONO (-6735 710);
FORCEPROP 0 LASTPIN (-5425 6400) $PN CL32
J 0
(-5415 6410);
DISPLAY 0.489362 (-5415 6410);
PAINT MONO (-5415 6410);
FORCEPROP 0 LASTPIN (-5425 6350) $PN CL33
J 0
(-5415 6360);
DISPLAY 0.489362 (-5415 6360);
PAINT MONO (-5415 6360);
FORCEPROP 0 LASTPIN (-5425 6300) $PN CL43
J 0
(-5415 6310);
DISPLAY 0.489362 (-5415 6310);
PAINT MONO (-5415 6310);
FORCEPROP 0 LASTPIN (-5425 6250) $PN CL44
J 0
(-5415 6260);
DISPLAY 0.489362 (-5415 6260);
PAINT MONO (-5415 6260);
FORCEPROP 0 LASTPIN (-5425 6200) $PN CL46
J 0
(-5415 6210);
DISPLAY 0.489362 (-5415 6210);
PAINT MONO (-5415 6210);
FORCEPROP 0 LASTPIN (-5425 6150) $PN CL47
J 0
(-5415 6160);
DISPLAY 0.489362 (-5415 6160);
PAINT MONO (-5415 6160);
FORCEPROP 0 LASTPIN (-5425 6100) $PN CN35
J 0
(-5415 6110);
DISPLAY 0.489362 (-5415 6110);
PAINT MONO (-5415 6110);
FORCEPROP 0 LASTPIN (-5425 6050) $PN CN36
J 0
(-5415 6060);
DISPLAY 0.489362 (-5415 6060);
PAINT MONO (-5415 6060);
FORCEPROP 0 LASTPIN (-5425 6000) $PN CN40
J 0
(-5415 6010);
DISPLAY 0.489362 (-5415 6010);
PAINT MONO (-5415 6010);
FORCEPROP 0 LASTPIN (-5425 5950) $PN CN41
J 0
(-5415 5960);
DISPLAY 0.489362 (-5415 5960);
PAINT MONO (-5415 5960);
FORCEPROP 0 LASTPIN (-5425 5900) $PN CP23
J 0
(-5415 5910);
DISPLAY 0.489362 (-5415 5910);
PAINT MONO (-5415 5910);
FORCEPROP 0 LASTPIN (-5425 5850) $PN CP24
J 0
(-5415 5860);
DISPLAY 0.489362 (-5415 5860);
PAINT MONO (-5415 5860);
FORCEPROP 0 LASTPIN (-5425 5800) $PN CP26
J 0
(-5415 5810);
DISPLAY 0.489362 (-5415 5810);
PAINT MONO (-5415 5810);
FORCEPROP 0 LASTPIN (-5425 5750) $PN CP27
J 0
(-5415 5760);
DISPLAY 0.489362 (-5415 5760);
PAINT MONO (-5415 5760);
FORCEPROP 0 LASTPIN (-5425 5700) $PN CP29
J 0
(-5415 5710);
DISPLAY 0.489362 (-5415 5710);
PAINT MONO (-5415 5710);
FORCEPROP 0 LASTPIN (-5425 5650) $PN CP30
J 0
(-5415 5660);
DISPLAY 0.489362 (-5415 5660);
PAINT MONO (-5415 5660);
FORCEPROP 0 LASTPIN (-5425 5600) $PN CP32
J 0
(-5415 5610);
DISPLAY 0.489362 (-5415 5610);
PAINT MONO (-5415 5610);
FORCEPROP 0 LASTPIN (-5425 5550) $PN CP33
J 0
(-5415 5560);
DISPLAY 0.489362 (-5415 5560);
PAINT MONO (-5415 5560);
FORCEPROP 0 LASTPIN (-5425 5500) $PN CP43
J 0
(-5415 5510);
DISPLAY 0.489362 (-5415 5510);
PAINT MONO (-5415 5510);
FORCEPROP 0 LASTPIN (-5425 5450) $PN CP44
J 0
(-5415 5460);
DISPLAY 0.489362 (-5415 5460);
PAINT MONO (-5415 5460);
FORCEPROP 0 LASTPIN (-5425 5400) $PN CP46
J 0
(-5415 5410);
DISPLAY 0.489362 (-5415 5410);
PAINT MONO (-5415 5410);
FORCEPROP 0 LASTPIN (-5425 5350) $PN CP47
J 0
(-5415 5360);
DISPLAY 0.489362 (-5415 5360);
PAINT MONO (-5415 5360);
FORCEPROP 0 LASTPIN (-5425 5300) $PN CP49
J 0
(-5415 5310);
DISPLAY 0.489362 (-5415 5310);
PAINT MONO (-5415 5310);
FORCEPROP 0 LASTPIN (-5425 5250) $PN CP50
J 0
(-5415 5260);
DISPLAY 0.489362 (-5415 5260);
PAINT MONO (-5415 5260);
FORCEPROP 0 LASTPIN (-5425 5200) $PN CP52
J 0
(-5415 5210);
DISPLAY 0.489362 (-5415 5210);
PAINT MONO (-5415 5210);
FORCEPROP 0 LASTPIN (-5425 5150) $PN CP53
J 0
(-5415 5160);
DISPLAY 0.489362 (-5415 5160);
PAINT MONO (-5415 5160);
FORCEPROP 0 LASTPIN (-5425 5100) $PN CU35
J 0
(-5415 5110);
DISPLAY 0.489362 (-5415 5110);
PAINT MONO (-5415 5110);
FORCEPROP 0 LASTPIN (-5425 5050) $PN CU36
J 0
(-5415 5060);
DISPLAY 0.489362 (-5415 5060);
PAINT MONO (-5415 5060);
FORCEPROP 0 LASTPIN (-5425 5000) $PN CU40
J 0
(-5415 5010);
DISPLAY 0.489362 (-5415 5010);
PAINT MONO (-5415 5010);
FORCEPROP 0 LASTPIN (-5425 4950) $PN CU41
J 0
(-5415 4960);
DISPLAY 0.489362 (-5415 4960);
PAINT MONO (-5415 4960);
FORCEPROP 0 LASTPIN (-5425 4900) $PN CV23
J 0
(-5415 4910);
DISPLAY 0.489362 (-5415 4910);
PAINT MONO (-5415 4910);
FORCEPROP 0 LASTPIN (-5425 4850) $PN CV24
J 0
(-5415 4860);
DISPLAY 0.489362 (-5415 4860);
PAINT MONO (-5415 4860);
FORCEPROP 0 LASTPIN (-5425 4800) $PN CV26
J 0
(-5415 4810);
DISPLAY 0.489362 (-5415 4810);
PAINT MONO (-5415 4810);
FORCEPROP 0 LASTPIN (-5425 4750) $PN CV27
J 0
(-5415 4760);
DISPLAY 0.489362 (-5415 4760);
PAINT MONO (-5415 4760);
FORCEPROP 0 LASTPIN (-5425 4700) $PN CV29
J 0
(-5415 4710);
DISPLAY 0.489362 (-5415 4710);
PAINT MONO (-5415 4710);
FORCEPROP 0 LASTPIN (-5425 4650) $PN CV30
J 0
(-5415 4660);
DISPLAY 0.489362 (-5415 4660);
PAINT MONO (-5415 4660);
FORCEPROP 0 LASTPIN (-5425 4600) $PN CV32
J 0
(-5415 4610);
DISPLAY 0.489362 (-5415 4610);
PAINT MONO (-5415 4610);
FORCEPROP 0 LASTPIN (-5425 4550) $PN CV33
J 0
(-5415 4560);
DISPLAY 0.489362 (-5415 4560);
PAINT MONO (-5415 4560);
FORCEPROP 0 LASTPIN (-5425 4500) $PN CV43
J 0
(-5415 4510);
DISPLAY 0.489362 (-5415 4510);
PAINT MONO (-5415 4510);
FORCEPROP 0 LASTPIN (-5425 4450) $PN CV44
J 0
(-5415 4460);
DISPLAY 0.489362 (-5415 4460);
PAINT MONO (-5415 4460);
FORCEPROP 0 LASTPIN (-5425 4400) $PN CV46
J 0
(-5415 4410);
DISPLAY 0.489362 (-5415 4410);
PAINT MONO (-5415 4410);
FORCEPROP 0 LASTPIN (-5425 4350) $PN CV47
J 0
(-5415 4360);
DISPLAY 0.489362 (-5415 4360);
PAINT MONO (-5415 4360);
FORCEPROP 0 LASTPIN (-5425 4300) $PN CV49
J 0
(-5415 4310);
DISPLAY 0.489362 (-5415 4310);
PAINT MONO (-5415 4310);
FORCEPROP 0 LASTPIN (-5425 4250) $PN CV50
J 0
(-5415 4260);
DISPLAY 0.489362 (-5415 4260);
PAINT MONO (-5415 4260);
FORCEPROP 0 LASTPIN (-5425 4200) $PN CV52
J 0
(-5415 4210);
DISPLAY 0.489362 (-5415 4210);
PAINT MONO (-5415 4210);
FORCEPROP 0 LASTPIN (-5425 4150) $PN CV53
J 0
(-5415 4160);
DISPLAY 0.489362 (-5415 4160);
PAINT MONO (-5415 4160);
FORCEPROP 0 LASTPIN (-5425 4100) $PN DA35
J 0
(-5415 4110);
DISPLAY 0.489362 (-5415 4110);
PAINT MONO (-5415 4110);
FORCEPROP 0 LASTPIN (-5425 4050) $PN DA36
J 0
(-5415 4060);
DISPLAY 0.489362 (-5415 4060);
PAINT MONO (-5415 4060);
FORCEPROP 0 LASTPIN (-5425 4000) $PN DA40
J 0
(-5415 4010);
DISPLAY 0.489362 (-5415 4010);
PAINT MONO (-5415 4010);
FORCEPROP 0 LASTPIN (-5425 3950) $PN DA41
J 0
(-5415 3960);
DISPLAY 0.489362 (-5415 3960);
PAINT MONO (-5415 3960);
FORCEPROP 0 LASTPIN (-5425 3900) $PN DB23
J 0
(-5415 3910);
DISPLAY 0.489362 (-5415 3910);
PAINT MONO (-5415 3910);
FORCEPROP 0 LASTPIN (-5425 3850) $PN DB24
J 0
(-5415 3860);
DISPLAY 0.489362 (-5415 3860);
PAINT MONO (-5415 3860);
FORCEPROP 0 LASTPIN (-5425 3800) $PN DB26
J 0
(-5415 3810);
DISPLAY 0.489362 (-5415 3810);
PAINT MONO (-5415 3810);
FORCEPROP 0 LASTPIN (-5425 3750) $PN DB27
J 0
(-5415 3760);
DISPLAY 0.489362 (-5415 3760);
PAINT MONO (-5415 3760);
FORCEPROP 0 LASTPIN (-5425 3700) $PN DB29
J 0
(-5415 3710);
DISPLAY 0.489362 (-5415 3710);
PAINT MONO (-5415 3710);
FORCEPROP 0 LASTPIN (-5425 3650) $PN DB30
J 0
(-5415 3660);
DISPLAY 0.489362 (-5415 3660);
PAINT MONO (-5415 3660);
FORCEPROP 0 LASTPIN (-5425 3600) $PN DB32
J 0
(-5415 3610);
DISPLAY 0.489362 (-5415 3610);
PAINT MONO (-5415 3610);
FORCEPROP 0 LASTPIN (-5425 3550) $PN DB33
J 0
(-5415 3560);
DISPLAY 0.489362 (-5415 3560);
PAINT MONO (-5415 3560);
FORCEPROP 0 LASTPIN (-5425 3500) $PN DB43
J 0
(-5415 3510);
DISPLAY 0.489362 (-5415 3510);
PAINT MONO (-5415 3510);
FORCEPROP 0 LASTPIN (-5425 3450) $PN DB44
J 0
(-5415 3460);
DISPLAY 0.489362 (-5415 3460);
PAINT MONO (-5415 3460);
FORCEPROP 0 LASTPIN (-5425 3400) $PN DB46
J 0
(-5415 3410);
DISPLAY 0.489362 (-5415 3410);
PAINT MONO (-5415 3410);
FORCEPROP 0 LASTPIN (-5425 3350) $PN DB47
J 0
(-5415 3360);
DISPLAY 0.489362 (-5415 3360);
PAINT MONO (-5415 3360);
FORCEPROP 0 LASTPIN (-5425 3300) $PN DB49
J 0
(-5415 3310);
DISPLAY 0.489362 (-5415 3310);
PAINT MONO (-5415 3310);
FORCEPROP 0 LASTPIN (-5425 3250) $PN DB50
J 0
(-5415 3260);
DISPLAY 0.489362 (-5415 3260);
PAINT MONO (-5415 3260);
FORCEPROP 0 LASTPIN (-5425 3200) $PN DB52
J 0
(-5415 3210);
DISPLAY 0.489362 (-5415 3210);
PAINT MONO (-5415 3210);
FORCEPROP 0 LASTPIN (-5425 3150) $PN DB53
J 0
(-5415 3160);
DISPLAY 0.489362 (-5415 3160);
PAINT MONO (-5415 3160);
FORCEPROP 0 LASTPIN (-5425 3100) $PN DC35
J 0
(-5415 3110);
DISPLAY 0.489362 (-5415 3110);
PAINT MONO (-5415 3110);
FORCEPROP 0 LASTPIN (-5425 3050) $PN DC36
J 0
(-5415 3060);
DISPLAY 0.489362 (-5415 3060);
PAINT MONO (-5415 3060);
FORCEPROP 0 LASTPIN (-5425 3000) $PN DC40
J 0
(-5415 3010);
DISPLAY 0.489362 (-5415 3010);
PAINT MONO (-5415 3010);
FORCEPROP 0 LASTPIN (-5425 2950) $PN DC41
J 0
(-5415 2960);
DISPLAY 0.489362 (-5415 2960);
PAINT MONO (-5415 2960);
FORCEPROP 0 LASTPIN (-5425 2900) $PN DD22
J 0
(-5415 2910);
DISPLAY 0.489362 (-5415 2910);
PAINT MONO (-5415 2910);
FORCEPROP 0 LASTPIN (-5425 2850) $PN DD25
J 0
(-5415 2860);
DISPLAY 0.489362 (-5415 2860);
PAINT MONO (-5415 2860);
FORCEPROP 0 LASTPIN (-5425 2800) $PN DD28
J 0
(-5415 2810);
DISPLAY 0.489362 (-5415 2810);
PAINT MONO (-5415 2810);
FORCEPROP 0 LASTPIN (-5425 2750) $PN DD31
J 0
(-5415 2760);
DISPLAY 0.489362 (-5415 2760);
PAINT MONO (-5415 2760);
FORCEPROP 0 LASTPIN (-5425 2700) $PN DD34
J 0
(-5415 2710);
DISPLAY 0.489362 (-5415 2710);
PAINT MONO (-5415 2710);
FORCEPROP 0 LASTPIN (-5425 2650) $PN DD42
J 0
(-5415 2660);
DISPLAY 0.489362 (-5415 2660);
PAINT MONO (-5415 2660);
FORCEPROP 0 LASTPIN (-5425 2600) $PN DD45
J 0
(-5415 2610);
DISPLAY 0.489362 (-5415 2610);
PAINT MONO (-5415 2610);
FORCEPROP 0 LASTPIN (-5425 2550) $PN DD48
J 0
(-5415 2560);
DISPLAY 0.489362 (-5415 2560);
PAINT MONO (-5415 2560);
FORCEPROP 0 LASTPIN (-5425 2500) $PN DD51
J 0
(-5415 2510);
DISPLAY 0.489362 (-5415 2510);
PAINT MONO (-5415 2510);
FORCEPROP 0 LASTPIN (-5425 2450) $PN DD54
J 0
(-5415 2460);
DISPLAY 0.489362 (-5415 2460);
PAINT MONO (-5415 2460);
FORCEPROP 0 LASTPIN (-5425 2400) $PN DE22
J 0
(-5415 2410);
DISPLAY 0.489362 (-5415 2410);
PAINT MONO (-5415 2410);
FORCEPROP 0 LASTPIN (-5425 2350) $PN DE25
J 0
(-5415 2360);
DISPLAY 0.489362 (-5415 2360);
PAINT MONO (-5415 2360);
FORCEPROP 0 LASTPIN (-5425 2300) $PN DE28
J 0
(-5415 2310);
DISPLAY 0.489362 (-5415 2310);
PAINT MONO (-5415 2310);
FORCEPROP 0 LASTPIN (-5425 2250) $PN DE31
J 0
(-5415 2260);
DISPLAY 0.489362 (-5415 2260);
PAINT MONO (-5415 2260);
FORCEPROP 0 LASTPIN (-5425 2200) $PN DE34
J 0
(-5415 2210);
DISPLAY 0.489362 (-5415 2210);
PAINT MONO (-5415 2210);
FORCEPROP 0 LASTPIN (-5425 2150) $PN DE35
J 0
(-5415 2160);
DISPLAY 0.489362 (-5415 2160);
PAINT MONO (-5415 2160);
FORCEPROP 0 LASTPIN (-5425 2100) $PN DE41
J 0
(-5415 2110);
DISPLAY 0.489362 (-5415 2110);
PAINT MONO (-5415 2110);
FORCEPROP 0 LASTPIN (-5425 2050) $PN DE42
J 0
(-5415 2060);
DISPLAY 0.489362 (-5415 2060);
PAINT MONO (-5415 2060);
FORCEPROP 0 LASTPIN (-5425 2000) $PN DE45
J 0
(-5415 2010);
DISPLAY 0.489362 (-5415 2010);
PAINT MONO (-5415 2010);
FORCEPROP 0 LASTPIN (-5425 1950) $PN DE48
J 0
(-5415 1960);
DISPLAY 0.489362 (-5415 1960);
PAINT MONO (-5415 1960);
FORCEPROP 0 LASTPIN (-5425 1900) $PN DE51
J 0
(-5415 1910);
DISPLAY 0.489362 (-5415 1910);
PAINT MONO (-5415 1910);
FORCEPROP 0 LASTPIN (-5425 1850) $PN DE54
J 0
(-5415 1860);
DISPLAY 0.489362 (-5415 1860);
PAINT MONO (-5415 1860);
FORCEPROP 0 LASTPIN (-5425 1800) $PN DG19
J 0
(-5415 1810);
DISPLAY 0.489362 (-5415 1810);
PAINT MONO (-5415 1810);
FORCEPROP 0 LASTPIN (-5425 1750) $PN DG57
J 0
(-5415 1760);
DISPLAY 0.489362 (-5415 1760);
PAINT MONO (-5415 1760);
FORCEPROP 0 LASTPIN (-5425 1700) $PN DH19
J 0
(-5415 1710);
DISPLAY 0.489362 (-5415 1710);
PAINT MONO (-5415 1710);
FORCEPROP 0 LASTPIN (-5425 1650) $PN DH20
J 0
(-5415 1660);
DISPLAY 0.489362 (-5415 1660);
PAINT MONO (-5415 1660);
FORCEPROP 0 LASTPIN (-5425 1600) $PN DH22
J 0
(-5415 1610);
DISPLAY 0.489362 (-5415 1610);
PAINT MONO (-5415 1610);
FORCEPROP 0 LASTPIN (-5425 1550) $PN DH23
J 0
(-5415 1560);
DISPLAY 0.489362 (-5415 1560);
PAINT MONO (-5415 1560);
FORCEPROP 0 LASTPIN (-5425 1500) $PN DH25
J 0
(-5415 1510);
DISPLAY 0.489362 (-5415 1510);
PAINT MONO (-5415 1510);
FORCEPROP 0 LASTPIN (-5425 1450) $PN DH26
J 0
(-5415 1460);
DISPLAY 0.489362 (-5415 1460);
PAINT MONO (-5415 1460);
FORCEPROP 0 LASTPIN (-5425 1400) $PN DH28
J 0
(-5415 1410);
DISPLAY 0.489362 (-5415 1410);
PAINT MONO (-5415 1410);
FORCEPROP 0 LASTPIN (-5425 1350) $PN DH29
J 0
(-5415 1360);
DISPLAY 0.489362 (-5415 1360);
PAINT MONO (-5415 1360);
FORCEPROP 0 LASTPIN (-5425 1300) $PN DH31
J 0
(-5415 1310);
DISPLAY 0.489362 (-5415 1310);
PAINT MONO (-5415 1310);
FORCEPROP 0 LASTPIN (-5425 1250) $PN DH32
J 0
(-5415 1260);
DISPLAY 0.489362 (-5415 1260);
PAINT MONO (-5415 1260);
FORCEPROP 0 LASTPIN (-5425 1200) $PN DH34
J 0
(-5415 1210);
DISPLAY 0.489362 (-5415 1210);
PAINT MONO (-5415 1210);
FORCEPROP 0 LASTPIN (-5425 1150) $PN DH35
J 0
(-5415 1160);
DISPLAY 0.489362 (-5415 1160);
PAINT MONO (-5415 1160);
FORCEPROP 0 LASTPIN (-5425 1100) $PN DH41
J 0
(-5415 1110);
DISPLAY 0.489362 (-5415 1110);
PAINT MONO (-5415 1110);
FORCEPROP 0 LASTPIN (-5425 1050) $PN DH42
J 0
(-5415 1060);
DISPLAY 0.489362 (-5415 1060);
PAINT MONO (-5415 1060);
FORCEPROP 0 LASTPIN (-5425 1000) $PN DH44
J 0
(-5415 1010);
DISPLAY 0.489362 (-5415 1010);
PAINT MONO (-5415 1010);
FORCEPROP 0 LASTPIN (-5425 950) $PN DH45
J 0
(-5415 960);
DISPLAY 0.489362 (-5415 960);
PAINT MONO (-5415 960);
FORCEPROP 0 LASTPIN (-5425 900) $PN DH47
J 0
(-5415 910);
DISPLAY 0.489362 (-5415 910);
PAINT MONO (-5415 910);
FORCEPROP 0 LASTPIN (-5425 850) $PN DH48
J 0
(-5415 860);
DISPLAY 0.489362 (-5415 860);
PAINT MONO (-5415 860);
FORCEPROP 0 LASTPIN (-5425 800) $PN DH50
J 0
(-5415 810);
DISPLAY 0.489362 (-5415 810);
PAINT MONO (-5415 810);
FORCEPROP 0 LASTPIN (-5425 750) $PN DH51
J 0
(-5415 760);
DISPLAY 0.489362 (-5415 760);
PAINT MONO (-5415 760);
FORCEPROP 0 LASTPIN (-5425 700) $PN DH53
J 0
(-5415 710);
DISPLAY 0.489362 (-5415 710);
PAINT MONO (-5415 710);
FORCEPROP 0 LASTPIN (-5425 650) $PN DH54
J 0
(-5415 660);
DISPLAY 0.489362 (-5415 660);
PAINT MONO (-5415 660);
FORCEPROP 0 LASTPIN (-5425 600) $PN DH56
J 0
(-5415 610);
DISPLAY 0.489362 (-5415 610);
PAINT MONO (-5415 610);
FORCEPROP 0 LASTPIN (-5425 550) $PN DH57
J 0
(-5415 560);
DISPLAY 0.489362 (-5415 560);
PAINT MONO (-5415 560);
FORCEPROP 2 LAST PART_TYPE SMLF
J 0
(-6800 6675);
DISPLAY 1.021277 (-6800 6675);
FORCEPROP 1 LAST MATERIAL IO
J 0
(-6570 6582);
DISPLAY 0.489362 (-6570 6582);
PAINT SKYBLUE (-6570 6582);
FORCEPROP 2 LAST VALUE SOCKET6096_13568-001
J 0
(-6800 6625);
DISPLAY 0.489362 (-6800 6625);
PAINT SKYBLUE (-6800 6625);
FORCEPROP 1 LAST CDS_LMAN_SYM_OUTLINE -500,3200,500,-3200
J 0
(-6075 3350);
DISPLAY 0.468085 (-6075 3350);
PAINT GREEN (-6075 3350);
DISPLAY INVISIBLE (-6075 3350);
FORCEPROP 2 LAST CDS_LIB pure_quanta
J 0
(-6075 3350);
DISPLAY INVISIBLE (-6075 3350);
FORCEPROP 1 LAST NEEDS_NO_SIZE TRUE
J 0
(-6075 3350);
DISPLAY 0.723404 (-6075 3350);
PAINT GREEN (-6075 3350);
DISPLAY INVISIBLE (-6075 3350);
FORCEPROP 1 LAST PATH I45
J 0
(-6075 3350);
DISPLAY 0.723404 (-6075 3350);
PAINT GREEN (-6075 3350);
DISPLAY INVISIBLE (-6075 3350);
FORCEPROP 1 LAST PART_NUMBER DGA^6000030
J 0
(-6570 6709);
DISPLAY 0.489362 (-6570 6709);
PAINT SKYBLUE (-6570 6709);
DISPLAY INVISIBLE (-6570 6709);
FORCEADD VCC_CORE..1
(-5275 6475);
FORCEPROP 3 LASTPIN (-5275 6425) SIG_NAME PVDDCR_CPU1_P0\g
J 0
(-5265 6435);
DISPLAY 0.659574 (-5265 6435);
PAINT MONO (-5265 6435);
DISPLAY INVISIBLE (-5265 6435);
FORCEPROP 1 LAST HDL_POWER PVDDCR_CPU1_P0
J 1
(-5275 6525);
DISPLAY 0.489362 (-5275 6525);
PAINT GREEN (-5275 6525);
FORCEPROP 2 LAST CDS_LIB pure_quanta_power
J 0
(-5275 6475);
DISPLAY INVISIBLE (-5275 6475);
FORCEPROP 1 LAST PATH I46
J 0
(-5225 6500);
DISPLAY 0.872340 (-5225 6500);
PAINT AQUA (-5225 6500);
DISPLAY INVISIBLE (-5225 6500);
FORCEADD VCC_CORE..1
(-6900 6225);
FORCEPROP 3 LASTPIN (-6900 6175) SIG_NAME PVDDCR_CPU1_P0\g
J 0
(-6890 6185);
DISPLAY 0.659574 (-6890 6185);
PAINT MONO (-6890 6185);
DISPLAY INVISIBLE (-6890 6185);
FORCEPROP 1 LAST HDL_POWER PVDDCR_CPU1_P0
J 1
(-6900 6275);
DISPLAY 0.489362 (-6900 6275);
PAINT GREEN (-6900 6275);
FORCEPROP 2 LAST CDS_LIB pure_quanta_power
J 0
(-6900 6225);
DISPLAY INVISIBLE (-6900 6225);
FORCEPROP 1 LAST PATH I47
J 0
(-6850 6250);
DISPLAY 0.872340 (-6850 6250);
PAINT AQUA (-6850 6250);
DISPLAY INVISIBLE (-6850 6250);
FORCEADD GENOA_SP5..26
(-4250 4575);
FORCEPROP 1 LAST LOCATION U25
J 0
(-4700 6375);
DISPLAY 0.489362 (-4700 6375);
PAINT SKYBLUE (-4700 6375);
FORCEPROP 0 LAST $SEC 26
J 0
(-4675 6575);
DISPLAY 0.680851 (-4675 6575);
PAINT MONO (-4675 6575);
DISPLAY INVISIBLE (-4675 6575);
FORCEPROP 0 LAST CDS_SEC 26
J 0
(-4700 6475);
DISPLAY 1.021277 (-4700 6475);
DISPLAY INVISIBLE (-4700 6475);
FORCEPROP 0 LASTPIN (-4850 4925) $PN AA22
J 2
(-4860 4935);
DISPLAY 0.489362 (-4860 4935);
PAINT MONO (-4860 4935);
FORCEPROP 0 LASTPIN (-4850 4875) $PN AC4
J 2
(-4860 4885);
DISPLAY 0.489362 (-4860 4885);
PAINT MONO (-4860 4885);
FORCEPROP 0 LASTPIN (-4850 4825) $PN AC11
J 2
(-4860 4835);
DISPLAY 0.489362 (-4860 4835);
PAINT MONO (-4860 4835);
FORCEPROP 0 LASTPIN (-4850 4775) $PN AC18
J 2
(-4860 4785);
DISPLAY 0.489362 (-4860 4785);
PAINT MONO (-4860 4785);
FORCEPROP 0 LASTPIN (-4850 4725) $PN AD22
J 2
(-4860 4735);
DISPLAY 0.489362 (-4860 4735);
PAINT MONO (-4860 4735);
FORCEPROP 0 LASTPIN (-4850 4675) $PN AF5
J 2
(-4860 4685);
DISPLAY 0.489362 (-4860 4685);
PAINT MONO (-4860 4685);
FORCEPROP 0 LASTPIN (-4850 4625) $PN AF12
J 2
(-4860 4635);
DISPLAY 0.489362 (-4860 4635);
PAINT MONO (-4860 4635);
FORCEPROP 0 LASTPIN (-4850 4575) $PN AF19
J 2
(-4860 4585);
DISPLAY 0.489362 (-4860 4585);
PAINT MONO (-4860 4585);
FORCEPROP 0 LASTPIN (-4850 4525) $PN AH22
J 2
(-4860 4535);
DISPLAY 0.489362 (-4860 4535);
PAINT MONO (-4860 4535);
FORCEPROP 0 LASTPIN (-4850 4475) $PN AJ4
J 2
(-4860 4485);
DISPLAY 0.489362 (-4860 4485);
PAINT MONO (-4860 4485);
FORCEPROP 0 LASTPIN (-4850 4425) $PN AJ11
J 2
(-4860 4435);
DISPLAY 0.489362 (-4860 4435);
PAINT MONO (-4860 4435);
FORCEPROP 0 LASTPIN (-4850 4375) $PN AJ18
J 2
(-4860 4385);
DISPLAY 0.489362 (-4860 4385);
PAINT MONO (-4860 4385);
FORCEPROP 0 LASTPIN (-4850 4325) $PN AM5
J 2
(-4860 4335);
DISPLAY 0.489362 (-4860 4335);
PAINT MONO (-4860 4335);
FORCEPROP 0 LASTPIN (-4850 4275) $PN AM12
J 2
(-4860 4285);
DISPLAY 0.489362 (-4860 4285);
PAINT MONO (-4860 4285);
FORCEPROP 0 LASTPIN (-4850 4225) $PN AM19
J 2
(-4860 4235);
DISPLAY 0.489362 (-4860 4235);
PAINT MONO (-4860 4235);
FORCEPROP 0 LASTPIN (-4850 4175) $PN AM22
J 2
(-4860 4185);
DISPLAY 0.489362 (-4860 4185);
PAINT MONO (-4860 4185);
FORCEPROP 0 LASTPIN (-4850 4125) $PN AR4
J 2
(-4860 4135);
DISPLAY 0.489362 (-4860 4135);
PAINT MONO (-4860 4135);
FORCEPROP 0 LASTPIN (-4850 4075) $PN AR11
J 2
(-4860 4085);
DISPLAY 0.489362 (-4860 4085);
PAINT MONO (-4860 4085);
FORCEPROP 0 LASTPIN (-4850 4025) $PN AR18
J 2
(-4860 4035);
DISPLAY 0.489362 (-4860 4035);
PAINT MONO (-4860 4035);
FORCEPROP 0 LASTPIN (-4850 3975) $PN AT22
J 2
(-4860 3985);
DISPLAY 0.489362 (-4860 3985);
PAINT MONO (-4860 3985);
FORCEPROP 0 LASTPIN (-4850 3925) $PN AU23
J 2
(-4860 3935);
DISPLAY 0.489362 (-4860 3935);
PAINT MONO (-4860 3935);
FORCEPROP 0 LASTPIN (-4850 3875) $PN AU27
J 2
(-4860 3885);
DISPLAY 0.489362 (-4860 3885);
PAINT MONO (-4860 3885);
FORCEPROP 0 LASTPIN (-4850 3825) $PN AU31
J 2
(-4860 3835);
DISPLAY 0.489362 (-4860 3835);
PAINT MONO (-4860 3835);
FORCEPROP 0 LASTPIN (-4850 3775) $PN AU35
J 2
(-4860 3785);
DISPLAY 0.489362 (-4860 3785);
PAINT MONO (-4860 3785);
FORCEPROP 0 LASTPIN (-4850 3725) $PN AU40
J 2
(-4860 3735);
DISPLAY 0.489362 (-4860 3735);
PAINT MONO (-4860 3735);
FORCEPROP 0 LASTPIN (-4850 3675) $PN AV5
J 2
(-4860 3685);
DISPLAY 0.489362 (-4860 3685);
PAINT MONO (-4860 3685);
FORCEPROP 0 LASTPIN (-4850 3625) $PN AV12
J 2
(-4860 3635);
DISPLAY 0.489362 (-4860 3635);
PAINT MONO (-4860 3635);
FORCEPROP 0 LASTPIN (-4850 3575) $PN AV19
J 2
(-4860 3585);
DISPLAY 0.489362 (-4860 3585);
PAINT MONO (-4860 3585);
FORCEPROP 0 LASTPIN (-4850 3525) $PN AV22
J 2
(-4860 3535);
DISPLAY 0.489362 (-4860 3535);
PAINT MONO (-4860 3535);
FORCEPROP 0 LASTPIN (-4850 3475) $PN AV24
J 2
(-4860 3485);
DISPLAY 0.489362 (-4860 3485);
PAINT MONO (-4860 3485);
FORCEPROP 0 LASTPIN (-4850 3425) $PN AV26
J 2
(-4860 3435);
DISPLAY 0.489362 (-4860 3435);
PAINT MONO (-4860 3435);
FORCEPROP 0 LASTPIN (-4850 3375) $PN AV28
J 2
(-4860 3385);
DISPLAY 0.489362 (-4860 3385);
PAINT MONO (-4860 3385);
FORCEPROP 0 LASTPIN (-4850 3325) $PN AV30
J 2
(-4860 3335);
DISPLAY 0.489362 (-4860 3335);
PAINT MONO (-4860 3335);
FORCEPROP 0 LASTPIN (-4850 3275) $PN AV32
J 2
(-4860 3285);
DISPLAY 0.489362 (-4860 3285);
PAINT MONO (-4860 3285);
FORCEPROP 0 LASTPIN (-4850 3225) $PN AV34
J 2
(-4860 3235);
DISPLAY 0.489362 (-4860 3235);
PAINT MONO (-4860 3235);
FORCEPROP 0 LASTPIN (-4850 3175) $PN AV36
J 2
(-4860 3185);
DISPLAY 0.489362 (-4860 3185);
PAINT MONO (-4860 3185);
FORCEPROP 0 LASTPIN (-4850 3125) $PN AV39
J 2
(-4860 3135);
DISPLAY 0.489362 (-4860 3135);
PAINT MONO (-4860 3135);
FORCEPROP 0 LASTPIN (-4850 3075) $PN AV41
J 2
(-4860 3085);
DISPLAY 0.489362 (-4860 3085);
PAINT MONO (-4860 3085);
FORCEPROP 0 LASTPIN (-3650 6025) $PN AV43
J 0
(-3640 6035);
DISPLAY 0.489362 (-3640 6035);
PAINT MONO (-3640 6035);
FORCEPROP 0 LASTPIN (-3650 5975) $PN AV45
J 0
(-3640 5985);
DISPLAY 0.489362 (-3640 5985);
PAINT MONO (-3640 5985);
FORCEPROP 0 LASTPIN (-3650 5925) $PN AV47
J 0
(-3640 5935);
DISPLAY 0.489362 (-3640 5935);
PAINT MONO (-3640 5935);
FORCEPROP 0 LASTPIN (-3650 5875) $PN AW23
J 0
(-3640 5885);
DISPLAY 0.489362 (-3640 5885);
PAINT MONO (-3640 5885);
FORCEPROP 0 LASTPIN (-3650 5825) $PN AW25
J 0
(-3640 5835);
DISPLAY 0.489362 (-3640 5835);
PAINT MONO (-3640 5835);
FORCEPROP 0 LASTPIN (-3650 5775) $PN AW27
J 0
(-3640 5785);
DISPLAY 0.489362 (-3640 5785);
PAINT MONO (-3640 5785);
FORCEPROP 0 LASTPIN (-3650 5725) $PN AW48
J 0
(-3640 5735);
DISPLAY 0.489362 (-3640 5735);
PAINT MONO (-3640 5735);
FORCEPROP 0 LASTPIN (-3650 5675) $PN AY22
J 0
(-3640 5685);
DISPLAY 0.489362 (-3640 5685);
PAINT MONO (-3640 5685);
FORCEPROP 0 LASTPIN (-3650 5625) $PN AY24
J 0
(-3640 5635);
DISPLAY 0.489362 (-3640 5635);
PAINT MONO (-3640 5635);
FORCEPROP 0 LASTPIN (-3650 5575) $PN AY26
J 0
(-3640 5585);
DISPLAY 0.489362 (-3640 5585);
PAINT MONO (-3640 5585);
FORCEPROP 0 LASTPIN (-3650 5525) $PN AY28
J 0
(-3640 5535);
DISPLAY 0.489362 (-3640 5535);
PAINT MONO (-3640 5535);
FORCEPROP 0 LASTPIN (-3650 5475) $PN AY49
J 0
(-3640 5485);
DISPLAY 0.489362 (-3640 5485);
PAINT MONO (-3640 5485);
FORCEPROP 0 LASTPIN (-4850 6025) $PN B5
J 2
(-4860 6035);
DISPLAY 0.489362 (-4860 6035);
PAINT MONO (-4860 6035);
FORCEPROP 0 LASTPIN (-3650 5425) $PN BA4
J 0
(-3640 5435);
DISPLAY 0.489362 (-3640 5435);
PAINT MONO (-3640 5435);
FORCEPROP 0 LASTPIN (-3650 5375) $PN BA11
J 0
(-3640 5385);
DISPLAY 0.489362 (-3640 5385);
PAINT MONO (-3640 5385);
FORCEPROP 0 LASTPIN (-3650 5325) $PN BA18
J 0
(-3640 5335);
DISPLAY 0.489362 (-3640 5335);
PAINT MONO (-3640 5335);
FORCEPROP 0 LASTPIN (-3650 5275) $PN BA23
J 0
(-3640 5285);
DISPLAY 0.489362 (-3640 5285);
PAINT MONO (-3640 5285);
FORCEPROP 0 LASTPIN (-3650 5225) $PN BA25
J 0
(-3640 5235);
DISPLAY 0.489362 (-3640 5235);
PAINT MONO (-3640 5235);
FORCEPROP 0 LASTPIN (-3650 5175) $PN BA27
J 0
(-3640 5185);
DISPLAY 0.489362 (-3640 5185);
PAINT MONO (-3640 5185);
FORCEPROP 0 LASTPIN (-3650 5125) $PN BA48
J 0
(-3640 5135);
DISPLAY 0.489362 (-3640 5135);
PAINT MONO (-3640 5135);
FORCEPROP 0 LASTPIN (-3650 5075) $PN BB22
J 0
(-3640 5085);
DISPLAY 0.489362 (-3640 5085);
PAINT MONO (-3640 5085);
FORCEPROP 0 LASTPIN (-3650 5025) $PN BB24
J 0
(-3640 5035);
DISPLAY 0.489362 (-3640 5035);
PAINT MONO (-3640 5035);
FORCEPROP 0 LASTPIN (-3650 4975) $PN BB26
J 0
(-3640 4985);
DISPLAY 0.489362 (-3640 4985);
PAINT MONO (-3640 4985);
FORCEPROP 0 LASTPIN (-3650 4925) $PN BB28
J 0
(-3640 4935);
DISPLAY 0.489362 (-3640 4935);
PAINT MONO (-3640 4935);
FORCEPROP 0 LASTPIN (-3650 4875) $PN BB49
J 0
(-3640 4885);
DISPLAY 0.489362 (-3640 4885);
PAINT MONO (-3640 4885);
FORCEPROP 0 LASTPIN (-3650 4825) $PN BC23
J 0
(-3640 4835);
DISPLAY 0.489362 (-3640 4835);
PAINT MONO (-3640 4835);
FORCEPROP 0 LASTPIN (-3650 4775) $PN BC25
J 0
(-3640 4785);
DISPLAY 0.489362 (-3640 4785);
PAINT MONO (-3640 4785);
FORCEPROP 0 LASTPIN (-3650 4725) $PN BC27
J 0
(-3640 4735);
DISPLAY 0.489362 (-3640 4735);
PAINT MONO (-3640 4735);
FORCEPROP 0 LASTPIN (-3650 4675) $PN BC48
J 0
(-3640 4685);
DISPLAY 0.489362 (-3640 4685);
PAINT MONO (-3640 4685);
FORCEPROP 0 LASTPIN (-3650 4625) $PN BD5
J 0
(-3640 4635);
DISPLAY 0.489362 (-3640 4635);
PAINT MONO (-3640 4635);
FORCEPROP 0 LASTPIN (-3650 4575) $PN BD12
J 0
(-3640 4585);
DISPLAY 0.489362 (-3640 4585);
PAINT MONO (-3640 4585);
FORCEPROP 0 LASTPIN (-3650 4525) $PN BD19
J 0
(-3640 4535);
DISPLAY 0.489362 (-3640 4535);
PAINT MONO (-3640 4535);
FORCEPROP 0 LASTPIN (-3650 4475) $PN BD22
J 0
(-3640 4485);
DISPLAY 0.489362 (-3640 4485);
PAINT MONO (-3640 4485);
FORCEPROP 0 LASTPIN (-3650 4425) $PN BD24
J 0
(-3640 4435);
DISPLAY 0.489362 (-3640 4435);
PAINT MONO (-3640 4435);
FORCEPROP 0 LASTPIN (-3650 4375) $PN BD26
J 0
(-3640 4385);
DISPLAY 0.489362 (-3640 4385);
PAINT MONO (-3640 4385);
FORCEPROP 0 LASTPIN (-3650 4325) $PN BD28
J 0
(-3640 4335);
DISPLAY 0.489362 (-3640 4335);
PAINT MONO (-3640 4335);
FORCEPROP 0 LASTPIN (-3650 4275) $PN BD48
J 0
(-3640 4285);
DISPLAY 0.489362 (-3640 4285);
PAINT MONO (-3640 4285);
FORCEPROP 0 LASTPIN (-3650 4225) $PN BF23
J 0
(-3640 4235);
DISPLAY 0.489362 (-3640 4235);
PAINT MONO (-3640 4235);
FORCEPROP 0 LASTPIN (-3650 4175) $PN BF25
J 0
(-3640 4185);
DISPLAY 0.489362 (-3640 4185);
PAINT MONO (-3640 4185);
FORCEPROP 0 LASTPIN (-3650 4125) $PN BF27
J 0
(-3640 4135);
DISPLAY 0.489362 (-3640 4135);
PAINT MONO (-3640 4135);
FORCEPROP 0 LASTPIN (-3650 4075) $PN BF48
J 0
(-3640 4085);
DISPLAY 0.489362 (-3640 4085);
PAINT MONO (-3640 4085);
FORCEPROP 0 LASTPIN (-3650 4025) $PN BG22
J 0
(-3640 4035);
DISPLAY 0.489362 (-3640 4035);
PAINT MONO (-3640 4035);
FORCEPROP 0 LASTPIN (-3650 3975) $PN BG24
J 0
(-3640 3985);
DISPLAY 0.489362 (-3640 3985);
PAINT MONO (-3640 3985);
FORCEPROP 0 LASTPIN (-3650 3925) $PN BG26
J 0
(-3640 3935);
DISPLAY 0.489362 (-3640 3935);
PAINT MONO (-3640 3935);
FORCEPROP 0 LASTPIN (-3650 3875) $PN BG28
J 0
(-3640 3885);
DISPLAY 0.489362 (-3640 3885);
PAINT MONO (-3640 3885);
FORCEPROP 0 LASTPIN (-3650 3825) $PN BG48
J 0
(-3640 3835);
DISPLAY 0.489362 (-3640 3835);
PAINT MONO (-3640 3835);
FORCEPROP 0 LASTPIN (-3650 3775) $PN BH23
J 0
(-3640 3785);
DISPLAY 0.489362 (-3640 3785);
PAINT MONO (-3640 3785);
FORCEPROP 0 LASTPIN (-3650 3725) $PN BH25
J 0
(-3640 3735);
DISPLAY 0.489362 (-3640 3735);
PAINT MONO (-3640 3735);
FORCEPROP 0 LASTPIN (-3650 3675) $PN BH48
J 0
(-3640 3685);
DISPLAY 0.489362 (-3640 3685);
PAINT MONO (-3640 3685);
FORCEPROP 0 LASTPIN (-3650 3625) $PN BJ4
J 0
(-3640 3635);
DISPLAY 0.489362 (-3640 3635);
PAINT MONO (-3640 3635);
FORCEPROP 0 LASTPIN (-3650 3575) $PN BJ11
J 0
(-3640 3585);
DISPLAY 0.489362 (-3640 3585);
PAINT MONO (-3640 3585);
FORCEPROP 0 LASTPIN (-3650 3525) $PN BJ48
J 0
(-3640 3535);
DISPLAY 0.489362 (-3640 3535);
PAINT MONO (-3640 3535);
FORCEPROP 0 LASTPIN (-3650 3475) $PN BM5
J 0
(-3640 3485);
DISPLAY 0.489362 (-3640 3485);
PAINT MONO (-3640 3485);
FORCEPROP 0 LASTPIN (-4850 5975) $PN C4
J 2
(-4860 5985);
DISPLAY 0.489362 (-4860 5985);
PAINT MONO (-4860 5985);
FORCEPROP 0 LASTPIN (-4850 5925) $PN E4
J 2
(-4860 5935);
DISPLAY 0.489362 (-4860 5935);
PAINT MONO (-4860 5935);
FORCEPROP 0 LASTPIN (-4850 5875) $PN E11
J 2
(-4860 5885);
DISPLAY 0.489362 (-4860 5885);
PAINT MONO (-4860 5885);
FORCEPROP 0 LASTPIN (-4850 5825) $PN H5
J 2
(-4860 5835);
DISPLAY 0.489362 (-4860 5835);
PAINT MONO (-4860 5835);
FORCEPROP 0 LASTPIN (-4850 5775) $PN H12
J 2
(-4860 5785);
DISPLAY 0.489362 (-4860 5785);
PAINT MONO (-4860 5785);
FORCEPROP 0 LASTPIN (-4850 5725) $PN H19
J 2
(-4860 5735);
DISPLAY 0.489362 (-4860 5735);
PAINT MONO (-4860 5735);
FORCEPROP 0 LASTPIN (-4850 5675) $PN K22
J 2
(-4860 5685);
DISPLAY 0.489362 (-4860 5685);
PAINT MONO (-4860 5685);
FORCEPROP 0 LASTPIN (-4850 5625) $PN L4
J 2
(-4860 5635);
DISPLAY 0.489362 (-4860 5635);
PAINT MONO (-4860 5635);
FORCEPROP 0 LASTPIN (-4850 5575) $PN L11
J 2
(-4860 5585);
DISPLAY 0.489362 (-4860 5585);
PAINT MONO (-4860 5585);
FORCEPROP 0 LASTPIN (-4850 5525) $PN L18
J 2
(-4860 5535);
DISPLAY 0.489362 (-4860 5535);
PAINT MONO (-4860 5535);
FORCEPROP 0 LASTPIN (-4850 5475) $PN P5
J 2
(-4860 5485);
DISPLAY 0.489362 (-4860 5485);
PAINT MONO (-4860 5485);
FORCEPROP 0 LASTPIN (-4850 5425) $PN P12
J 2
(-4860 5435);
DISPLAY 0.489362 (-4860 5435);
PAINT MONO (-4860 5435);
FORCEPROP 0 LASTPIN (-4850 5375) $PN P19
J 2
(-4860 5385);
DISPLAY 0.489362 (-4860 5385);
PAINT MONO (-4860 5385);
FORCEPROP 0 LASTPIN (-4850 5325) $PN P22
J 2
(-4860 5335);
DISPLAY 0.489362 (-4860 5335);
PAINT MONO (-4860 5335);
FORCEPROP 0 LASTPIN (-4850 5275) $PN U4
J 2
(-4860 5285);
DISPLAY 0.489362 (-4860 5285);
PAINT MONO (-4860 5285);
FORCEPROP 0 LASTPIN (-4850 5225) $PN U11
J 2
(-4860 5235);
DISPLAY 0.489362 (-4860 5235);
PAINT MONO (-4860 5235);
FORCEPROP 0 LASTPIN (-4850 5175) $PN U18
J 2
(-4860 5185);
DISPLAY 0.489362 (-4860 5185);
PAINT MONO (-4860 5185);
FORCEPROP 0 LASTPIN (-4850 5125) $PN V22
J 2
(-4860 5135);
DISPLAY 0.489362 (-4860 5135);
PAINT MONO (-4860 5135);
FORCEPROP 0 LASTPIN (-4850 5075) $PN Y5
J 2
(-4860 5085);
DISPLAY 0.489362 (-4860 5085);
PAINT MONO (-4860 5085);
FORCEPROP 0 LASTPIN (-4850 5025) $PN Y12
J 2
(-4860 5035);
DISPLAY 0.489362 (-4860 5035);
PAINT MONO (-4860 5035);
FORCEPROP 0 LASTPIN (-4850 4975) $PN Y19
J 2
(-4860 4985);
DISPLAY 0.489362 (-4860 4985);
PAINT MONO (-4860 4985);
FORCEPROP 2 LAST PART_TYPE SMLF
J 0
(-4700 6525);
DISPLAY 1.021277 (-4700 6525);
FORCEPROP 1 LAST MATERIAL IO
J 0
(-4695 6257);
DISPLAY 0.489362 (-4695 6257);
PAINT SKYBLUE (-4695 6257);
FORCEPROP 2 LAST VALUE SOCKET6096_13568-001
J 0
(-4700 6325);
DISPLAY 0.489362 (-4700 6325);
PAINT SKYBLUE (-4700 6325);
FORCEPROP 1 LAST CDS_LMAN_SYM_OUTLINE -450,1650,450,-1650
J 0
(-4250 4575);
DISPLAY 0.468085 (-4250 4575);
PAINT GREEN (-4250 4575);
DISPLAY INVISIBLE (-4250 4575);
FORCEPROP 1 LAST NEEDS_NO_SIZE TRUE
J 0
(-4250 4575);
DISPLAY 0.723404 (-4250 4575);
PAINT GREEN (-4250 4575);
DISPLAY INVISIBLE (-4250 4575);
FORCEPROP 2 LAST CDS_LIB pure_quanta
J 0
(-4250 4575);
DISPLAY INVISIBLE (-4250 4575);
FORCEPROP 1 LAST PATH I50
J 0
(-4250 4575);
DISPLAY 0.723404 (-4250 4575);
PAINT GREEN (-4250 4575);
DISPLAY INVISIBLE (-4250 4575);
FORCEPROP 1 LAST PART_NUMBER DGA^6000030
J 0
(-4700 6450);
DISPLAY 0.489362 (-4700 6450);
PAINT SKYBLUE (-4700 6450);
DISPLAY INVISIBLE (-4700 6450);
FORCEADD VCC_CORE..1
(-8900 6575);
FORCEPROP 3 LASTPIN (-8900 6525) SIG_NAME PVDDCR_CPU0_P0\g
J 0
(-8890 6535);
DISPLAY 0.659574 (-8890 6535);
PAINT MONO (-8890 6535);
DISPLAY INVISIBLE (-8890 6535);
FORCEPROP 1 LAST HDL_POWER PVDDCR_CPU0_P0
J 1
(-8900 6625);
DISPLAY 0.489362 (-8900 6625);
PAINT GREEN (-8900 6625);
FORCEPROP 2 LAST CDS_LIB pure_quanta_power
J 0
(-8900 6575);
DISPLAY INVISIBLE (-8900 6575);
FORCEPROP 1 LAST PATH I51
J 0
(-8850 6600);
DISPLAY 0.872340 (-8850 6600);
PAINT AQUA (-8850 6600);
DISPLAY INVISIBLE (-8850 6600);
FORCEADD VCC_CORE..1
(-3300 6600);
FORCEPROP 3 LASTPIN (-3300 6550) SIG_NAME PVDD11_S3_P0\g
J 0
(-3290 6560);
DISPLAY 0.659574 (-3290 6560);
PAINT MONO (-3290 6560);
DISPLAY INVISIBLE (-3290 6560);
FORCEPROP 1 LAST HDL_POWER PVDD11_S3_P0
J 1
(-3300 6650);
DISPLAY 0.489362 (-3300 6650);
PAINT GREEN (-3300 6650);
FORCEPROP 2 LAST CDS_LIB pure_quanta_power
J 0
(-3300 6600);
DISPLAY INVISIBLE (-3300 6600);
FORCEPROP 1 LAST PATH I52
J 0
(-3250 6625);
DISPLAY 0.872340 (-3250 6625);
PAINT AQUA (-3250 6625);
DISPLAY INVISIBLE (-3250 6625);
FORCEADD UNIVERSAL_POWER..1
(-3475 2825);
FORCEPROP 3 LASTPIN (-3475 2775) SIG_NAME PVDD18_S5_P0\g
J 0
(-3465 2785);
DISPLAY 0.659574 (-3465 2785);
PAINT MONO (-3465 2785);
DISPLAY INVISIBLE (-3465 2785);
FORCEPROP 1 LAST HDL_POWER PVDD18_S5_P0
J 1
(-3475 2875);
DISPLAY 0.489362 (-3475 2875);
PAINT GREEN (-3475 2875);
FORCEPROP 2 LAST CDS_LIB pure_quanta_power
J 0
(-3475 2825);
DISPLAY INVISIBLE (-3475 2825);
FORCEPROP 1 LAST PATH I53
J 0
(-3425 2850);
DISPLAY 0.872340 (-3425 2850);
PAINT AQUA (-3425 2850);
DISPLAY INVISIBLE (-3425 2850);
FORCEADD UNIVERSAL_POWER..1
(-3475 1075);
FORCEPROP 3 LASTPIN (-3475 1025) SIG_NAME PVDD_33_S5\g
J 0
(-3465 1035);
DISPLAY 0.659574 (-3465 1035);
PAINT MONO (-3465 1035);
DISPLAY INVISIBLE (-3465 1035);
FORCEPROP 1 LAST HDL_POWER PVDD_33_S5
J 1
(-3475 1125);
DISPLAY 0.489362 (-3475 1125);
PAINT GREEN (-3475 1125);
FORCEPROP 2 LAST CDS_LIB pure_quanta_power
J 0
(-3475 1075);
DISPLAY INVISIBLE (-3475 1075);
FORCEPROP 1 LAST PATH I55
J 0
(-3425 1100);
DISPLAY 0.872340 (-3425 1100);
PAINT AQUA (-3425 1100);
DISPLAY INVISIBLE (-3425 1100);
FORCEADD VCC_CORE..1
(-3500 6150);
FORCEPROP 3 LASTPIN (-3500 6100) SIG_NAME PVDDCR_SOC_P0\g
J 0
(-3490 6110);
DISPLAY 0.659574 (-3490 6110);
PAINT MONO (-3490 6110);
DISPLAY INVISIBLE (-3490 6110);
FORCEPROP 1 LAST HDL_POWER PVDDCR_SOC_P0
J 1
(-3500 6200);
DISPLAY 0.489362 (-3500 6200);
PAINT GREEN (-3500 6200);
FORCEPROP 2 LAST CDS_LIB pure_quanta_power
J 0
(-3500 6150);
DISPLAY INVISIBLE (-3500 6150);
FORCEPROP 1 LAST PATH I56
J 0
(-3450 6175);
DISPLAY 0.872340 (-3450 6175);
PAINT AQUA (-3450 6175);
DISPLAY INVISIBLE (-3450 6175);
FORCEADD VCC_CORE..1
(-4975 6150);
FORCEPROP 3 LASTPIN (-4975 6100) SIG_NAME PVDDCR_SOC_P0\g
J 0
(-4965 6110);
DISPLAY 0.659574 (-4965 6110);
PAINT MONO (-4965 6110);
DISPLAY INVISIBLE (-4965 6110);
FORCEPROP 1 LAST HDL_POWER PVDDCR_SOC_P0
J 1
(-4975 6200);
DISPLAY 0.489362 (-4975 6200);
PAINT GREEN (-4975 6200);
FORCEPROP 2 LAST CDS_LIB pure_quanta_power
J 0
(-4975 6150);
DISPLAY INVISIBLE (-4975 6150);
FORCEPROP 1 LAST PATH I57
J 0
(-4925 6175);
DISPLAY 0.872340 (-4925 6175);
PAINT AQUA (-4925 6175);
DISPLAY INVISIBLE (-4925 6175);
FORCEADD QUANTA_TITLE_BLOCK_C..1
(-100 100);
FORCEPROP 0 LAST CDS_CON_LAST_MODIFIED Thu Sep 14 16:11:53 2023
J 0
(-1985 115);
DISPLAY INVISIBLE (-1985 115);
FORCEPROP 1 LAST CUSTOM_TXT_CDS <CON_LAST_MODIFIED>
J 0
(-1985 115);
DISPLAY 0.978723 (-1985 115);
FORCEPROP 2 LAST CUSTOM_TXT_CDS <XR_PAGE_TITLE>
J 0
(-7990 5350);
DISPLAY 0.638298 (-7990 5350);
PAINT PINK (-7990 5350);
DISPLAY INVISIBLE (-7990 5350);
FORCEPROP 1 LAST CUSTOM_TXT_CDS <NAME_2>
J 0
(-3275 150);
FORCEPROP 1 LAST CUSTOM_TXT_CDS <NAME_1>
J 0
(-3275 275);
FORCEPROP 1 LAST CUSTOM_TXT_CDS <Q_NUMBER>
J 0
(-1503 203);
DISPLAY 1.212766 (-1503 203);
FORCEPROP 1 LAST CUSTOM_TXT_CDS <Q_PROJ>
J 0
(-2482 202);
DISPLAY 1.212766 (-2482 202);
FORCEPROP 1 LAST CUSTOM_TXT_CDS <Q_REV>
J 0
(-284 203);
DISPLAY 1.212766 (-284 203);
FORCEPROP 1 LAST CUSTOM_TXT_CDS <CON_PAGE_NUM> OF <CON_TOTAL_PAGES>
J 0
(-546 118);
DISPLAY 0.978723 (-546 118);
FORCEPROP 1 LAST Q_TITLE CPU0 POWER
J 0
(-9350 175);
DISPLAY 1.574468 (-9350 175);
PAINT GREEN (-9350 175);
FORCEPROP 2 LAST PAGE_BORDER TRUE
J 0
(-7990 5350);
DISPLAY 0.638298 (-7990 5350);
PAINT PINK (-7990 5350);
DISPLAY INVISIBLE (-7990 5350);
FORCEPROP 1 LAST CDS_LMAN_SYM_OUTLINE -9475,6775,100,-125
J 0
(-100 100);
DISPLAY 0.468085 (-100 100);
PAINT GREEN (-100 100);
DISPLAY INVISIBLE (-100 100);
FORCEPROP 2 LAST CDS_LIB pure_quanta
J 0
(-100 100);
DISPLAY INVISIBLE (-100 100);
FORCEPROP 2 LAST CDS_XR_PAGE_TITLE CR-30 : @T6G_MB_LIB.T6G(SCH_1):PAGE30
J 0
(-7990 5350);
DISPLAY 0.638298 (-7990 5350);
PAINT PINK (-7990 5350);
DISPLAY INVISIBLE (-7990 5350);
FORCEPROP 1 LAST Q_DEPT BU9
J 1
(-3863 149);
DISPLAY 1.957447 (-3863 149);
PAINT GREEN (-3863 149);
DISPLAY INVISIBLE (-3863 149);
FORCEPROP 1 LAST COMMENT_BODY TRUE
J 0
(-88 87);
DISPLAY 0.978723 (-88 87);
PAINT GREEN (-88 87);
DISPLAY INVISIBLE (-88 87);
WIRE 16 -1 (-1825 625)(-1475 625);
WIRE 16 -1 (-1475 625)(-1475 775);
WIRE 16 -1 (-8900 6325)(-8700 6325);
WIRE 16 -1 (-8900 6525)(-8900 6325);
WIRE 16 -1 (-8900 6325)(-8900 6275);
WIRE 16 -1 (-8900 6275)(-8700 6275);
WIRE 16 -1 (-8900 6275)(-8900 6225);
WIRE 16 -1 (-8900 6225)(-8700 6225);
WIRE 16 -1 (-8900 6225)(-8900 6175);
WIRE 16 -1 (-8900 6175)(-8700 6175);
WIRE 16 -1 (-8900 6175)(-8900 6125);
WIRE 16 -1 (-8700 6125)(-8900 6125);
WIRE 16 -1 (-8900 6125)(-8900 6075);
WIRE 16 -1 (-8900 6075)(-8700 6075);
WIRE 16 -1 (-8900 6075)(-8900 6025);
WIRE 16 -1 (-8900 6025)(-8700 6025);
WIRE 16 -1 (-8900 6025)(-8900 5975);
WIRE 16 -1 (-8900 5975)(-8700 5975);
WIRE 16 -1 (-8900 5975)(-8900 5925);
WIRE 16 -1 (-8900 5925)(-8700 5925);
WIRE 16 -1 (-8900 5925)(-8900 5875);
WIRE 16 -1 (-8900 5875)(-8700 5875);
WIRE 16 -1 (-8900 5875)(-8900 5825);
WIRE 16 -1 (-8900 5825)(-8700 5825);
WIRE 16 -1 (-8900 5825)(-8900 5775);
WIRE 16 -1 (-8900 5775)(-8700 5775);
WIRE 16 -1 (-8900 5775)(-8900 5725);
WIRE 16 -1 (-8900 5725)(-8700 5725);
WIRE 16 -1 (-8900 5725)(-8900 5675);
WIRE 16 -1 (-8900 5675)(-8700 5675);
WIRE 16 -1 (-8900 5675)(-8900 5625);
WIRE 16 -1 (-8900 5625)(-8700 5625);
WIRE 16 -1 (-8900 5625)(-8900 5575);
WIRE 16 -1 (-8900 5575)(-8700 5575);
WIRE 16 -1 (-8900 5575)(-8900 5525);
WIRE 16 -1 (-8900 5525)(-8700 5525);
WIRE 16 -1 (-8900 5525)(-8900 5475);
WIRE 16 -1 (-8900 5475)(-8700 5475);
WIRE 16 -1 (-8900 5475)(-8900 5425);
WIRE 16 -1 (-8900 5425)(-8700 5425);
WIRE 16 -1 (-8900 5425)(-8900 5375);
WIRE 16 -1 (-8900 5375)(-8700 5375);
WIRE 16 -1 (-8900 5375)(-8900 5325);
WIRE 16 -1 (-8900 5325)(-8700 5325);
WIRE 16 -1 (-8900 5325)(-8900 5275);
WIRE 16 -1 (-8900 5275)(-8700 5275);
WIRE 16 -1 (-8900 5275)(-8900 5225);
WIRE 16 -1 (-8900 5225)(-8700 5225);
WIRE 16 -1 (-8900 5225)(-8900 5175);
WIRE 16 -1 (-8900 5175)(-8700 5175);
WIRE 16 -1 (-8900 5175)(-8900 5125);
WIRE 16 -1 (-8900 5125)(-8700 5125);
WIRE 16 -1 (-8900 5125)(-8900 5075);
WIRE 16 -1 (-8700 5075)(-8900 5075);
WIRE 16 -1 (-8900 5075)(-8900 5025);
WIRE 16 -1 (-8900 5025)(-8700 5025);
WIRE 16 -1 (-8900 5025)(-8900 4975);
WIRE 16 -1 (-8900 4975)(-8700 4975);
WIRE 16 -1 (-8900 4975)(-8900 4925);
WIRE 16 -1 (-8900 4925)(-8700 4925);
WIRE 16 -1 (-8900 4925)(-8900 4875);
WIRE 16 -1 (-8900 4875)(-8700 4875);
WIRE 16 -1 (-8900 4875)(-8900 4825);
WIRE 16 -1 (-8900 4825)(-8700 4825);
WIRE 16 -1 (-8900 4825)(-8900 4775);
WIRE 16 -1 (-8900 4775)(-8700 4775);
WIRE 16 -1 (-8900 4775)(-8900 4725);
WIRE 16 -1 (-8900 4725)(-8700 4725);
WIRE 16 -1 (-8900 4725)(-8900 4675);
WIRE 16 -1 (-8900 4675)(-8700 4675);
WIRE 16 -1 (-8900 4675)(-8900 4625);
WIRE 16 -1 (-8900 4625)(-8700 4625);
WIRE 16 -1 (-8900 4625)(-8900 4575);
WIRE 16 -1 (-8900 4575)(-8700 4575);
WIRE 16 -1 (-8900 4575)(-8900 4525);
WIRE 16 -1 (-8900 4525)(-8700 4525);
WIRE 16 -1 (-8900 4525)(-8900 4475);
WIRE 16 -1 (-8900 4475)(-8700 4475);
WIRE 16 -1 (-8900 4475)(-8900 4425);
WIRE 16 -1 (-8900 4425)(-8700 4425);
WIRE 16 -1 (-8900 4425)(-8900 4375);
WIRE 16 -1 (-8900 4375)(-8700 4375);
WIRE 16 -1 (-8900 4375)(-8900 4325);
WIRE 16 -1 (-8900 4325)(-8700 4325);
WIRE 16 -1 (-8900 4325)(-8900 4275);
WIRE 16 -1 (-8900 4275)(-8700 4275);
WIRE 16 -1 (-8900 4275)(-8900 4225);
WIRE 16 -1 (-8900 4225)(-8700 4225);
WIRE 16 -1 (-8900 4225)(-8900 4175);
WIRE 16 -1 (-8900 4175)(-8700 4175);
WIRE 16 -1 (-8900 4175)(-8900 4125);
WIRE 16 -1 (-8900 4125)(-8700 4125);
WIRE 16 -1 (-8900 4125)(-8900 4075);
WIRE 16 -1 (-8700 4075)(-8900 4075);
WIRE 16 -1 (-8900 4075)(-8900 4025);
WIRE 16 -1 (-8900 4025)(-8700 4025);
WIRE 16 -1 (-8900 4025)(-8900 3975);
WIRE 16 -1 (-8900 3975)(-8700 3975);
WIRE 16 -1 (-8900 3975)(-8900 3925);
WIRE 16 -1 (-8900 3925)(-8700 3925);
WIRE 16 -1 (-8900 3925)(-8900 3875);
WIRE 16 -1 (-8900 3875)(-8700 3875);
WIRE 16 -1 (-8900 3875)(-8900 3825);
WIRE 16 -1 (-8900 3825)(-8700 3825);
WIRE 16 -1 (-8900 3825)(-8900 3775);
WIRE 16 -1 (-8900 3775)(-8700 3775);
WIRE 16 -1 (-8900 3775)(-8900 3725);
WIRE 16 -1 (-8900 3725)(-8700 3725);
WIRE 16 -1 (-8900 3725)(-8900 3675);
WIRE 16 -1 (-8900 3675)(-8700 3675);
WIRE 16 -1 (-8900 3675)(-8900 3625);
WIRE 16 -1 (-8900 3625)(-8700 3625);
WIRE 16 -1 (-8900 3625)(-8900 3575);
WIRE 16 -1 (-8900 3575)(-8700 3575);
WIRE 16 -1 (-8900 3575)(-8900 3525);
WIRE 16 -1 (-8900 3525)(-8700 3525);
WIRE 16 -1 (-8900 3525)(-8900 3475);
WIRE 16 -1 (-8900 3475)(-8700 3475);
WIRE 16 -1 (-8900 3475)(-8900 3425);
WIRE 16 -1 (-8900 3425)(-8700 3425);
WIRE 16 -1 (-8900 3425)(-8900 3375);
WIRE 16 -1 (-8900 3375)(-8700 3375);
WIRE 16 -1 (-8900 3375)(-8900 3325);
WIRE 16 -1 (-8900 3325)(-8700 3325);
WIRE 16 -1 (-8900 3325)(-8900 3275);
WIRE 16 -1 (-8900 3275)(-8700 3275);
WIRE 16 -1 (-8900 3275)(-8900 3225);
WIRE 16 -1 (-8900 3225)(-8700 3225);
WIRE 16 -1 (-8900 3225)(-8900 3175);
WIRE 16 -1 (-8900 3175)(-8700 3175);
WIRE 16 -1 (-8900 3175)(-8900 3125);
WIRE 16 -1 (-8900 3125)(-8700 3125);
WIRE 16 -1 (-8900 3125)(-8900 3075);
WIRE 16 -1 (-8900 3075)(-8700 3075);
WIRE 16 -1 (-8900 3075)(-8900 3025);
WIRE 16 -1 (-8700 3025)(-8900 3025);
WIRE 16 -1 (-8900 3025)(-8900 2975);
WIRE 16 -1 (-8900 2975)(-8700 2975);
WIRE 16 -1 (-8900 2975)(-8900 2925);
WIRE 16 -1 (-8900 2925)(-8700 2925);
WIRE 16 -1 (-8900 2925)(-8900 2875);
WIRE 16 -1 (-8900 2875)(-8700 2875);
WIRE 16 -1 (-8900 2875)(-8900 2825);
WIRE 16 -1 (-8900 2825)(-8700 2825);
WIRE 16 -1 (-8900 2825)(-8900 2775);
WIRE 16 -1 (-8900 2775)(-8700 2775);
WIRE 16 -1 (-8900 2775)(-8900 2725);
WIRE 16 -1 (-8900 2725)(-8700 2725);
WIRE 16 -1 (-8900 2725)(-8900 2675);
WIRE 16 -1 (-8900 2675)(-8700 2675);
WIRE 16 -1 (-8900 2675)(-8900 2625);
WIRE 16 -1 (-8900 2625)(-8700 2625);
WIRE 16 -1 (-8900 2625)(-8900 2575);
WIRE 16 -1 (-8900 2575)(-8700 2575);
WIRE 16 -1 (-8900 2575)(-8900 2525);
WIRE 16 -1 (-8900 2525)(-8700 2525);
WIRE 16 -1 (-8900 2525)(-8900 2475);
WIRE 16 -1 (-8900 2475)(-8700 2475);
WIRE 16 -1 (-8900 2475)(-8900 2425);
WIRE 16 -1 (-8900 2425)(-8700 2425);
WIRE 16 -1 (-8900 2425)(-8900 2375);
WIRE 16 -1 (-8900 2375)(-8700 2375);
WIRE 16 -1 (-8900 2375)(-8900 2325);
WIRE 16 -1 (-8900 2325)(-8700 2325);
WIRE 16 -1 (-8900 2325)(-8900 2275);
WIRE 16 -1 (-8900 2275)(-8700 2275);
WIRE 16 -1 (-8900 2275)(-8900 2225);
WIRE 16 -1 (-8900 2225)(-8700 2225);
WIRE 16 -1 (-8900 2225)(-8900 2175);
WIRE 16 -1 (-8900 2175)(-8700 2175);
WIRE 16 -1 (-8900 2175)(-8900 2125);
WIRE 16 -1 (-8900 2125)(-8700 2125);
WIRE 16 -1 (-8900 2125)(-8900 2075);
WIRE 16 -1 (-8900 2075)(-8700 2075);
WIRE 16 -1 (-8900 2075)(-8900 2025);
WIRE 16 -1 (-8700 2025)(-8900 2025);
WIRE 16 -1 (-8900 2025)(-8900 1975);
WIRE 16 -1 (-8900 1975)(-8700 1975);
WIRE 16 -1 (-8900 1975)(-8900 1925);
WIRE 16 -1 (-8900 1925)(-8700 1925);
WIRE 16 -1 (-8900 1925)(-8900 1875);
WIRE 16 -1 (-8900 1875)(-8700 1875);
WIRE 16 -1 (-8900 1875)(-8900 1825);
WIRE 16 -1 (-8900 1825)(-8700 1825);
WIRE 16 -1 (-8900 1825)(-8900 1775);
WIRE 16 -1 (-8900 1775)(-8700 1775);
WIRE 16 -1 (-8900 1775)(-8900 1725);
WIRE 16 -1 (-8900 1725)(-8700 1725);
WIRE 16 -1 (-8900 1725)(-8900 1675);
WIRE 16 -1 (-8900 1675)(-8700 1675);
WIRE 16 -1 (-8900 1675)(-8900 1625);
WIRE 16 -1 (-8900 1625)(-8700 1625);
WIRE 16 -1 (-8900 1625)(-8900 1575);
WIRE 16 -1 (-8900 1575)(-8700 1575);
WIRE 16 -1 (-8900 1575)(-8900 1525);
WIRE 16 -1 (-8900 1525)(-8700 1525);
WIRE 16 -1 (-8900 1525)(-8900 1475);
WIRE 16 -1 (-8900 1475)(-8700 1475);
WIRE 16 -1 (-8900 1475)(-8900 1425);
WIRE 16 -1 (-8900 1425)(-8700 1425);
WIRE 16 -1 (-8900 1425)(-8900 1375);
WIRE 16 -1 (-8900 1375)(-8700 1375);
WIRE 16 -1 (-8900 1375)(-8900 1325);
WIRE 16 -1 (-8900 1325)(-8700 1325);
WIRE 16 -1 (-8900 1325)(-8900 1275);
WIRE 16 -1 (-8900 1275)(-8700 1275);
WIRE 16 -1 (-8900 1275)(-8900 1225);
WIRE 16 -1 (-8900 1225)(-8700 1225);
WIRE 16 -1 (-8900 1225)(-8900 1175);
WIRE 16 -1 (-8900 1175)(-8700 1175);
WIRE 16 -1 (-8900 1175)(-8900 1125);
WIRE 16 -1 (-8900 1125)(-8700 1125);
WIRE 16 -1 (-8900 1125)(-8900 1075);
WIRE 16 -1 (-8900 1075)(-8700 1075);
WIRE 16 -1 (-8900 1075)(-8900 1025);
WIRE 16 -1 (-8900 1025)(-8700 1025);
WIRE 16 -1 (-8900 1025)(-8900 975);
WIRE 16 -1 (-8700 975)(-8900 975);
WIRE 16 -1 (-8900 975)(-8900 925);
WIRE 16 -1 (-8900 925)(-8700 925);
WIRE 16 -1 (-8900 925)(-8900 875);
WIRE 16 -1 (-8900 875)(-8700 875);
WIRE 16 -1 (-8900 875)(-8900 825);
WIRE 16 -1 (-8900 825)(-8700 825);
WIRE 16 -1 (-8900 825)(-8900 775);
WIRE 16 -1 (-8900 775)(-8700 775);
WIRE 16 -1 (-8900 775)(-8900 725);
WIRE 16 -1 (-8900 725)(-8700 725);
WIRE 16 -1 (-8900 725)(-8900 675);
WIRE 16 -1 (-8900 675)(-8700 675);
WIRE 16 -1 (-8900 675)(-8900 625);
WIRE 16 -1 (-8900 625)(-8700 625);
WIRE 16 -1 (-8900 625)(-8900 575);
WIRE 16 -1 (-8900 575)(-8700 575);
WIRE 16 -1 (-7400 6325)(-7250 6325);
WIRE 16 -1 (-7250 6525)(-7250 6325);
WIRE 16 -1 (-7250 6275)(-7250 6325);
WIRE 16 -1 (-7250 6275)(-7250 6225);
WIRE 16 -1 (-7400 6275)(-7250 6275);
WIRE 16 -1 (-7250 6225)(-7250 6175);
WIRE 16 -1 (-7400 6225)(-7250 6225);
WIRE 16 -1 (-7400 6175)(-7250 6175);
WIRE 16 -1 (-7250 6175)(-7250 6125);
WIRE 16 -1 (-7250 6125)(-7250 6075);
WIRE 16 -1 (-7400 6125)(-7250 6125);
WIRE 16 -1 (-7250 6075)(-7250 6025);
WIRE 16 -1 (-7400 6075)(-7250 6075);
WIRE 16 -1 (-7250 6025)(-7250 5975);
WIRE 16 -1 (-7400 6025)(-7250 6025);
WIRE 16 -1 (-7250 5975)(-7250 5925);
WIRE 16 -1 (-7400 5975)(-7250 5975);
WIRE 16 -1 (-7400 5925)(-7250 5925);
WIRE 16 -1 (-7250 5925)(-7250 5875);
WIRE 16 -1 (-7250 5825)(-7250 5875);
WIRE 16 -1 (-7400 5875)(-7250 5875);
WIRE 16 -1 (-7250 5825)(-7250 5775);
WIRE 16 -1 (-7400 5825)(-7250 5825);
WIRE 16 -1 (-7250 5775)(-7250 5725);
WIRE 16 -1 (-7400 5775)(-7250 5775);
WIRE 16 -1 (-7250 5725)(-7250 5675);
WIRE 16 -1 (-7400 5725)(-7250 5725);
WIRE 16 -1 (-7400 5675)(-7250 5675);
WIRE 16 -1 (-7250 5675)(-7250 5625);
WIRE 16 -1 (-7250 5625)(-7250 5575);
WIRE 16 -1 (-7400 5625)(-7250 5625);
WIRE 16 -1 (-7250 5575)(-7250 5525);
WIRE 16 -1 (-7400 5575)(-7250 5575);
WIRE 16 -1 (-7250 5525)(-7250 5475);
WIRE 16 -1 (-7400 5525)(-7250 5525);
WIRE 16 -1 (-7250 5475)(-7250 5425);
WIRE 16 -1 (-7400 5475)(-7250 5475);
WIRE 16 -1 (-7400 5425)(-7250 5425);
WIRE 16 -1 (-7250 5375)(-7250 5425);
WIRE 16 -1 (-7250 5375)(-7250 5325);
WIRE 16 -1 (-7400 5375)(-7250 5375);
WIRE 16 -1 (-7250 5325)(-7250 5275);
WIRE 16 -1 (-7400 5325)(-7250 5325);
WIRE 16 -1 (-7250 5275)(-7250 5225);
WIRE 16 -1 (-7400 5275)(-7250 5275);
WIRE 16 -1 (-7250 5225)(-7250 5175);
WIRE 16 -1 (-7400 5225)(-7250 5225);
WIRE 16 -1 (-7250 5175)(-7250 5125);
WIRE 16 -1 (-7400 5175)(-7250 5175);
WIRE 16 -1 (-7400 5125)(-7250 5125);
WIRE 16 -1 (-7250 5125)(-7250 5075);
WIRE 16 -1 (-7250 5075)(-7250 5025);
WIRE 16 -1 (-7400 5075)(-7250 5075);
WIRE 16 -1 (-7250 5025)(-7250 4975);
WIRE 16 -1 (-7400 5025)(-7250 5025);
WIRE 16 -1 (-7250 4925)(-7250 4975);
WIRE 16 -1 (-7400 4975)(-7250 4975);
WIRE 16 -1 (-7250 4925)(-7250 4875);
WIRE 16 -1 (-7400 4925)(-7250 4925);
WIRE 16 -1 (-7400 4875)(-7250 4875);
WIRE 16 -1 (-7250 4875)(-7250 4825);
WIRE 16 -1 (-7250 4825)(-7250 4775);
WIRE 16 -1 (-7400 4825)(-7250 4825);
WIRE 16 -1 (-7250 4775)(-7250 4725);
WIRE 16 -1 (-7400 4775)(-7250 4775);
WIRE 16 -1 (-7250 4725)(-7250 4675);
WIRE 16 -1 (-7400 4725)(-7250 4725);
WIRE 16 -1 (-7250 4675)(-7250 4625);
WIRE 16 -1 (-7400 4675)(-7250 4675);
WIRE 16 -1 (-7400 4625)(-7250 4625);
WIRE 16 -1 (-7250 4625)(-7250 4575);
WIRE 16 -1 (-7250 4575)(-7250 4525);
WIRE 16 -1 (-7400 4575)(-7250 4575);
WIRE 16 -1 (-7250 4475)(-7250 4525);
WIRE 16 -1 (-7400 4525)(-7250 4525);
WIRE 16 -1 (-7250 4475)(-7250 4425);
WIRE 16 -1 (-7400 4475)(-7250 4475);
WIRE 16 -1 (-7250 4425)(-7250 4375);
WIRE 16 -1 (-7400 4425)(-7250 4425);
WIRE 16 -1 (-7400 4375)(-7250 4375);
WIRE 16 -1 (-7250 4375)(-7250 4325);
WIRE 16 -1 (-7250 4325)(-7250 4275);
WIRE 16 -1 (-7400 4325)(-7250 4325);
WIRE 16 -1 (-7250 4275)(-7250 4225);
WIRE 16 -1 (-7400 4275)(-7250 4275);
WIRE 16 -1 (-7250 4225)(-7250 4175);
WIRE 16 -1 (-7400 4225)(-7250 4225);
WIRE 16 -1 (-7250 4175)(-7250 4125);
WIRE 16 -1 (-7400 4175)(-7250 4175);
WIRE 16 -1 (-7400 4125)(-7250 4125);
WIRE 16 -1 (-7250 4125)(-7250 4075);
WIRE 16 -1 (-7250 4025)(-7250 4075);
WIRE 16 -1 (-7400 4075)(-7250 4075);
WIRE 16 -1 (-7250 4025)(-7250 3975);
WIRE 16 -1 (-7400 4025)(-7250 4025);
WIRE 16 -1 (-7250 3975)(-7250 3925);
WIRE 16 -1 (-7400 3975)(-7250 3975);
WIRE 16 -1 (-7250 3925)(-7250 3875);
WIRE 16 -1 (-7400 3925)(-7250 3925);
WIRE 16 -1 (-7400 3875)(-7250 3875);
WIRE 16 -1 (-7250 3875)(-7250 3825);
WIRE 16 -1 (-7250 3825)(-7250 3775);
WIRE 16 -1 (-7400 3825)(-7250 3825);
WIRE 16 -1 (-7250 3775)(-7250 3725);
WIRE 16 -1 (-7400 3775)(-7250 3775);
WIRE 16 -1 (-7250 3725)(-7250 3675);
WIRE 16 -1 (-7400 3725)(-7250 3725);
WIRE 16 -1 (-7250 3675)(-7250 3625);
WIRE 16 -1 (-7400 3675)(-7250 3675);
WIRE 16 -1 (-7400 3625)(-7250 3625);
WIRE 16 -1 (-7250 3575)(-7250 3625);
WIRE 16 -1 (-7250 3575)(-7250 3525);
WIRE 16 -1 (-7400 3575)(-7250 3575);
WIRE 16 -1 (-7250 3525)(-7250 3475);
WIRE 16 -1 (-7400 3525)(-7250 3525);
WIRE 16 -1 (-7250 3475)(-7250 3425);
WIRE 16 -1 (-7400 3475)(-7250 3475);
WIRE 16 -1 (-7250 3425)(-7250 3375);
WIRE 16 -1 (-7400 3425)(-7250 3425);
WIRE 16 -1 (-7400 3375)(-7250 3375);
WIRE 16 -1 (-7250 3375)(-7250 3325);
WIRE 16 -1 (-7250 3325)(-7250 3275);
WIRE 16 -1 (-7400 3325)(-7250 3325);
WIRE 16 -1 (-7250 3275)(-7250 3225);
WIRE 16 -1 (-7400 3275)(-7250 3275);
WIRE 16 -1 (-7250 3225)(-7250 3175);
WIRE 16 -1 (-7400 3225)(-7250 3225);
WIRE 16 -1 (-7250 3125)(-7250 3175);
WIRE 16 -1 (-7400 3175)(-7250 3175);
WIRE 16 -1 (-7250 3125)(-7250 3075);
WIRE 16 -1 (-7400 3125)(-7250 3125);
WIRE 16 -1 (-7400 3075)(-7250 3075);
WIRE 16 -1 (-7250 3075)(-7250 3025);
WIRE 16 -1 (-7250 3025)(-7250 2975);
WIRE 16 -1 (-7400 3025)(-7250 3025);
WIRE 16 -1 (-7250 2975)(-7250 2925);
WIRE 16 -1 (-7400 2975)(-7250 2975);
WIRE 16 -1 (-7250 2925)(-7250 2875);
WIRE 16 -1 (-7400 2925)(-7250 2925);
WIRE 16 -1 (-7250 2875)(-7250 2825);
WIRE 16 -1 (-7400 2875)(-7250 2875);
WIRE 16 -1 (-7400 2825)(-7250 2825);
WIRE 16 -1 (-7250 2825)(-7250 2775);
WIRE 16 -1 (-7250 2775)(-7250 2725);
WIRE 16 -1 (-7400 2775)(-7250 2775);
WIRE 16 -1 (-7250 2675)(-7250 2725);
WIRE 16 -1 (-7400 2725)(-7250 2725);
WIRE 16 -1 (-7250 2675)(-7250 2625);
WIRE 16 -1 (-7400 2675)(-7250 2675);
WIRE 16 -1 (-7250 2625)(-7250 2575);
WIRE 16 -1 (-7400 2625)(-7250 2625);
WIRE 16 -1 (-7400 2575)(-7250 2575);
WIRE 16 -1 (-7250 2575)(-7250 2525);
WIRE 16 -1 (-7250 2525)(-7250 2475);
WIRE 16 -1 (-7400 2525)(-7250 2525);
WIRE 16 -1 (-7250 2475)(-7250 2425);
WIRE 16 -1 (-7400 2475)(-7250 2475);
WIRE 16 -1 (-7250 2425)(-7250 2375);
WIRE 16 -1 (-7400 2425)(-7250 2425);
WIRE 16 -1 (-7250 2375)(-7250 2325);
WIRE 16 -1 (-7400 2375)(-7250 2375);
WIRE 16 -1 (-7400 2325)(-7250 2325);
WIRE 16 -1 (-7250 2325)(-7250 2275);
WIRE 16 -1 (-7250 2225)(-7250 2275);
WIRE 16 -1 (-7400 2275)(-7250 2275);
WIRE 16 -1 (-7250 2225)(-7250 2175);
WIRE 16 -1 (-7400 2225)(-7250 2225);
WIRE 16 -1 (-7250 2175)(-7250 2125);
WIRE 16 -1 (-7400 2175)(-7250 2175);
WIRE 16 -1 (-7250 2125)(-7250 2075);
WIRE 16 -1 (-7400 2125)(-7250 2125);
WIRE 16 -1 (-7400 2075)(-7250 2075);
WIRE 16 -1 (-7250 2075)(-7250 2025);
WIRE 16 -1 (-7250 2025)(-7250 1975);
WIRE 16 -1 (-7400 2025)(-7250 2025);
WIRE 16 -1 (-7250 1975)(-7250 1925);
WIRE 16 -1 (-7400 1975)(-7250 1975);
WIRE 16 -1 (-7250 1925)(-7250 1875);
WIRE 16 -1 (-7400 1925)(-7250 1925);
WIRE 16 -1 (-7250 1875)(-7250 1825);
WIRE 16 -1 (-7400 1875)(-7250 1875);
WIRE 16 -1 (-7400 1825)(-7250 1825);
WIRE 16 -1 (-7250 1775)(-7250 1825);
WIRE 16 -1 (-7250 1775)(-7250 1725);
WIRE 16 -1 (-7400 1775)(-7250 1775);
WIRE 16 -1 (-7250 1725)(-7250 1675);
WIRE 16 -1 (-7400 1725)(-7250 1725);
WIRE 16 -1 (-7250 1675)(-7250 1625);
WIRE 16 -1 (-7400 1675)(-7250 1675);
WIRE 16 -1 (-7250 1625)(-7250 1575);
WIRE 16 -1 (-7400 1625)(-7250 1625);
WIRE 16 -1 (-7400 1575)(-7250 1575);
WIRE 16 -1 (-7250 1575)(-7250 1525);
WIRE 16 -1 (-7250 1525)(-7250 1475);
WIRE 16 -1 (-7400 1525)(-7250 1525);
WIRE 16 -1 (-7250 1475)(-7250 1425);
WIRE 16 -1 (-7400 1475)(-7250 1475);
WIRE 16 -1 (-7250 1425)(-7250 1375);
WIRE 16 -1 (-7400 1425)(-7250 1425);
WIRE 16 -1 (-7250 1325)(-7250 1375);
WIRE 16 -1 (-7400 1375)(-7250 1375);
WIRE 16 -1 (-7400 1325)(-7250 1325);
WIRE 16 -1 (-7250 1325)(-7250 1275);
WIRE 16 -1 (-7250 1275)(-7250 1225);
WIRE 16 -1 (-7400 1275)(-7250 1275);
WIRE 16 -1 (-7250 1225)(-7250 1175);
WIRE 16 -1 (-7400 1225)(-7250 1225);
WIRE 16 -1 (-7250 1175)(-7250 1125);
WIRE 16 -1 (-7400 1175)(-7250 1175);
WIRE 16 -1 (-7250 1125)(-7250 1075);
WIRE 16 -1 (-7400 1125)(-7250 1125);
WIRE 16 -1 (-7250 1075)(-7250 1025);
WIRE 16 -1 (-7400 1075)(-7250 1075);
WIRE 16 -1 (-7400 1025)(-7250 1025);
WIRE 16 -1 (-7250 1025)(-7250 975);
WIRE 16 -1 (-7250 975)(-7250 925);
WIRE 16 -1 (-7400 975)(-7250 975);
WIRE 16 -1 (-7250 875)(-7250 925);
WIRE 16 -1 (-7400 925)(-7250 925);
WIRE 16 -1 (-7250 875)(-7250 825);
WIRE 16 -1 (-7400 875)(-7250 875);
WIRE 16 -1 (-7250 825)(-7250 775);
WIRE 16 -1 (-7400 825)(-7250 825);
WIRE 16 -1 (-7400 775)(-7250 775);
WIRE 16 -1 (-7250 775)(-7250 725);
WIRE 16 -1 (-7250 725)(-7250 675);
WIRE 16 -1 (-7400 725)(-7250 725);
WIRE 16 -1 (-7250 675)(-7250 625);
WIRE 16 -1 (-7400 675)(-7250 675);
WIRE 16 -1 (-7250 625)(-7250 575);
WIRE 16 -1 (-7400 625)(-7250 625);
WIRE 16 -1 (-7250 575)(-7250 525);
WIRE 16 -1 (-7400 575)(-7250 575);
WIRE 16 -1 (-7400 525)(-7250 525);
WIRE 16 -1 (-6900 6175)(-6900 6100);
WIRE 16 -1 (-6900 6100)(-6725 6100);
WIRE 16 -1 (-6900 6100)(-6900 6050);
WIRE 16 -1 (-6900 6050)(-6725 6050);
WIRE 16 -1 (-6900 6050)(-6900 6000);
WIRE 16 -1 (-6725 6000)(-6900 6000);
WIRE 16 -1 (-6900 6000)(-6900 5950);
WIRE 16 -1 (-6900 5950)(-6725 5950);
WIRE 16 -1 (-6900 5950)(-6900 5900);
WIRE 16 -1 (-6900 5900)(-6725 5900);
WIRE 16 -1 (-6900 5900)(-6900 5850);
WIRE 16 -1 (-6900 5850)(-6725 5850);
WIRE 16 -1 (-6900 5850)(-6900 5800);
WIRE 16 -1 (-6900 5800)(-6725 5800);
WIRE 16 -1 (-6900 5800)(-6900 5750);
WIRE 16 -1 (-6725 5750)(-6900 5750);
WIRE 16 -1 (-6900 5750)(-6900 5700);
WIRE 16 -1 (-6900 5700)(-6725 5700);
WIRE 16 -1 (-6900 5700)(-6900 5650);
WIRE 16 -1 (-6900 5650)(-6725 5650);
WIRE 16 -1 (-6900 5650)(-6900 5600);
WIRE 16 -1 (-6900 5600)(-6725 5600);
WIRE 16 -1 (-6900 5600)(-6900 5550);
WIRE 16 -1 (-6900 5550)(-6725 5550);
WIRE 16 -1 (-6900 5550)(-6900 5500);
WIRE 16 -1 (-6725 5500)(-6900 5500);
WIRE 16 -1 (-6900 5500)(-6900 5450);
WIRE 16 -1 (-6900 5450)(-6725 5450);
WIRE 16 -1 (-6900 5450)(-6900 5400);
WIRE 16 -1 (-6900 5400)(-6725 5400);
WIRE 16 -1 (-6900 5400)(-6900 5350);
WIRE 16 -1 (-6900 5350)(-6725 5350);
WIRE 16 -1 (-6900 5350)(-6900 5300);
WIRE 16 -1 (-6900 5300)(-6725 5300);
WIRE 16 -1 (-6900 5300)(-6900 5250);
WIRE 16 -1 (-6725 5250)(-6900 5250);
WIRE 16 -1 (-6900 5250)(-6900 5200);
WIRE 16 -1 (-6900 5200)(-6725 5200);
WIRE 16 -1 (-6900 5200)(-6900 5150);
WIRE 16 -1 (-6900 5150)(-6725 5150);
WIRE 16 -1 (-6900 5150)(-6900 5100);
WIRE 16 -1 (-6900 5100)(-6725 5100);
WIRE 16 -1 (-6900 5100)(-6900 5050);
WIRE 16 -1 (-6900 5050)(-6725 5050);
WIRE 16 -1 (-6900 5050)(-6900 5000);
WIRE 16 -1 (-6900 5000)(-6725 5000);
WIRE 16 -1 (-6900 5000)(-6900 4950);
WIRE 16 -1 (-6725 4950)(-6900 4950);
WIRE 16 -1 (-6900 4950)(-6900 4900);
WIRE 16 -1 (-6900 4900)(-6725 4900);
WIRE 16 -1 (-6900 4900)(-6900 4850);
WIRE 16 -1 (-6900 4850)(-6725 4850);
WIRE 16 -1 (-6900 4850)(-6900 4800);
WIRE 16 -1 (-6900 4800)(-6725 4800);
WIRE 16 -1 (-6900 4800)(-6900 4750);
WIRE 16 -1 (-6900 4750)(-6725 4750);
WIRE 16 -1 (-6900 4750)(-6900 4700);
WIRE 16 -1 (-6725 4700)(-6900 4700);
WIRE 16 -1 (-6900 4700)(-6900 4650);
WIRE 16 -1 (-6900 4650)(-6725 4650);
WIRE 16 -1 (-6900 4650)(-6900 4600);
WIRE 16 -1 (-6900 4600)(-6725 4600);
WIRE 16 -1 (-6900 4600)(-6900 4550);
WIRE 16 -1 (-6900 4550)(-6725 4550);
WIRE 16 -1 (-6900 4550)(-6900 4500);
WIRE 16 -1 (-6900 4500)(-6725 4500);
WIRE 16 -1 (-6900 4500)(-6900 4450);
WIRE 16 -1 (-6725 4450)(-6900 4450);
WIRE 16 -1 (-6900 4450)(-6900 4400);
WIRE 16 -1 (-6900 4400)(-6725 4400);
WIRE 16 -1 (-6900 4400)(-6900 4350);
WIRE 16 -1 (-6900 4350)(-6725 4350);
WIRE 16 -1 (-6900 4350)(-6900 4300);
WIRE 16 -1 (-6900 4300)(-6725 4300);
WIRE 16 -1 (-6900 4300)(-6900 4250);
WIRE 16 -1 (-6900 4250)(-6725 4250);
WIRE 16 -1 (-6900 4250)(-6900 4200);
WIRE 16 -1 (-6725 4200)(-6900 4200);
WIRE 16 -1 (-6900 4200)(-6900 4150);
WIRE 16 -1 (-6900 4150)(-6725 4150);
WIRE 16 -1 (-6900 4150)(-6900 4100);
WIRE 16 -1 (-6900 4100)(-6725 4100);
WIRE 16 -1 (-6900 4100)(-6900 4050);
WIRE 16 -1 (-6900 4050)(-6725 4050);
WIRE 16 -1 (-6900 4050)(-6900 4000);
WIRE 16 -1 (-6900 4000)(-6725 4000);
WIRE 16 -1 (-6900 4000)(-6900 3950);
WIRE 16 -1 (-6725 3950)(-6900 3950);
WIRE 16 -1 (-6900 3950)(-6900 3900);
WIRE 16 -1 (-6900 3900)(-6725 3900);
WIRE 16 -1 (-6900 3900)(-6900 3850);
WIRE 16 -1 (-6900 3850)(-6725 3850);
WIRE 16 -1 (-6900 3850)(-6900 3800);
WIRE 16 -1 (-6900 3800)(-6725 3800);
WIRE 16 -1 (-6900 3800)(-6900 3750);
WIRE 16 -1 (-6900 3750)(-6725 3750);
WIRE 16 -1 (-6900 3750)(-6900 3700);
WIRE 16 -1 (-6725 3700)(-6900 3700);
WIRE 16 -1 (-6900 3700)(-6900 3650);
WIRE 16 -1 (-6900 3650)(-6725 3650);
WIRE 16 -1 (-6900 3650)(-6900 3600);
WIRE 16 -1 (-6900 3600)(-6725 3600);
WIRE 16 -1 (-6900 3600)(-6900 3550);
WIRE 16 -1 (-6900 3550)(-6725 3550);
WIRE 16 -1 (-6900 3550)(-6900 3500);
WIRE 16 -1 (-6900 3500)(-6725 3500);
WIRE 16 -1 (-6900 3500)(-6900 3450);
WIRE 16 -1 (-6725 3450)(-6900 3450);
WIRE 16 -1 (-6900 3450)(-6900 3400);
WIRE 16 -1 (-6900 3400)(-6725 3400);
WIRE 16 -1 (-6900 3400)(-6900 3350);
WIRE 16 -1 (-6900 3350)(-6725 3350);
WIRE 16 -1 (-6900 3350)(-6900 3300);
WIRE 16 -1 (-6900 3300)(-6725 3300);
WIRE 16 -1 (-6900 3300)(-6900 3250);
WIRE 16 -1 (-6900 3250)(-6725 3250);
WIRE 16 -1 (-6900 3250)(-6900 3200);
WIRE 16 -1 (-6725 3200)(-6900 3200);
WIRE 16 -1 (-6900 3200)(-6900 3150);
WIRE 16 -1 (-6900 3150)(-6725 3150);
WIRE 16 -1 (-6900 3150)(-6900 3100);
WIRE 16 -1 (-6900 3100)(-6725 3100);
WIRE 16 -1 (-6900 3100)(-6900 3050);
WIRE 16 -1 (-6900 3050)(-6725 3050);
WIRE 16 -1 (-6900 3050)(-6900 3000);
WIRE 16 -1 (-6900 3000)(-6725 3000);
WIRE 16 -1 (-6900 3000)(-6900 2950);
WIRE 16 -1 (-6900 2950)(-6725 2950);
WIRE 16 -1 (-6900 2950)(-6900 2900);
WIRE 16 -1 (-6725 2900)(-6900 2900);
WIRE 16 -1 (-6900 2900)(-6900 2850);
WIRE 16 -1 (-6900 2850)(-6725 2850);
WIRE 16 -1 (-6900 2850)(-6900 2800);
WIRE 16 -1 (-6900 2800)(-6725 2800);
WIRE 16 -1 (-6900 2800)(-6900 2750);
WIRE 16 -1 (-6900 2750)(-6725 2750);
WIRE 16 -1 (-6900 2750)(-6900 2700);
WIRE 16 -1 (-6900 2700)(-6725 2700);
WIRE 16 -1 (-6900 2700)(-6900 2650);
WIRE 16 -1 (-6725 2650)(-6900 2650);
WIRE 16 -1 (-6900 2650)(-6900 2600);
WIRE 16 -1 (-6900 2600)(-6725 2600);
WIRE 16 -1 (-6900 2600)(-6900 2550);
WIRE 16 -1 (-6900 2550)(-6725 2550);
WIRE 16 -1 (-6900 2550)(-6900 2500);
WIRE 16 -1 (-6900 2500)(-6725 2500);
WIRE 16 -1 (-6900 2500)(-6900 2450);
WIRE 16 -1 (-6900 2450)(-6725 2450);
WIRE 16 -1 (-6900 2450)(-6900 2400);
WIRE 16 -1 (-6725 2400)(-6900 2400);
WIRE 16 -1 (-6900 2400)(-6900 2350);
WIRE 16 -1 (-6900 2350)(-6725 2350);
WIRE 16 -1 (-6900 2350)(-6900 2300);
WIRE 16 -1 (-6900 2300)(-6725 2300);
WIRE 16 -1 (-6900 2300)(-6900 2250);
WIRE 16 -1 (-6900 2250)(-6725 2250);
WIRE 16 -1 (-6900 2250)(-6900 2200);
WIRE 16 -1 (-6900 2200)(-6725 2200);
WIRE 16 -1 (-6900 2200)(-6900 2150);
WIRE 16 -1 (-6725 2150)(-6900 2150);
WIRE 16 -1 (-6900 2150)(-6900 2100);
WIRE 16 -1 (-6900 2100)(-6725 2100);
WIRE 16 -1 (-6900 2100)(-6900 2050);
WIRE 16 -1 (-6900 2050)(-6725 2050);
WIRE 16 -1 (-6900 2050)(-6900 2000);
WIRE 16 -1 (-6900 2000)(-6725 2000);
WIRE 16 -1 (-6900 2000)(-6900 1950);
WIRE 16 -1 (-6900 1950)(-6725 1950);
WIRE 16 -1 (-6900 1950)(-6900 1900);
WIRE 16 -1 (-6725 1900)(-6900 1900);
WIRE 16 -1 (-6900 1900)(-6900 1850);
WIRE 16 -1 (-6900 1850)(-6725 1850);
WIRE 16 -1 (-6900 1850)(-6900 1800);
WIRE 16 -1 (-6900 1800)(-6725 1800);
WIRE 16 -1 (-6900 1800)(-6900 1750);
WIRE 16 -1 (-6900 1750)(-6725 1750);
WIRE 16 -1 (-6900 1750)(-6900 1700);
WIRE 16 -1 (-6900 1700)(-6725 1700);
WIRE 16 -1 (-6900 1700)(-6900 1650);
WIRE 16 -1 (-6725 1650)(-6900 1650);
WIRE 16 -1 (-6900 1650)(-6900 1600);
WIRE 16 -1 (-6900 1600)(-6725 1600);
WIRE 16 -1 (-6900 1600)(-6900 1550);
WIRE 16 -1 (-6900 1550)(-6725 1550);
WIRE 16 -1 (-6900 1550)(-6900 1500);
WIRE 16 -1 (-6900 1500)(-6725 1500);
WIRE 16 -1 (-6900 1500)(-6900 1450);
WIRE 16 -1 (-6900 1450)(-6725 1450);
WIRE 16 -1 (-6900 1450)(-6900 1400);
WIRE 16 -1 (-6725 1400)(-6900 1400);
WIRE 16 -1 (-6900 1400)(-6900 1350);
WIRE 16 -1 (-6900 1350)(-6725 1350);
WIRE 16 -1 (-6900 1350)(-6900 1300);
WIRE 16 -1 (-6900 1300)(-6725 1300);
WIRE 16 -1 (-6900 1300)(-6900 1250);
WIRE 16 -1 (-6900 1250)(-6725 1250);
WIRE 16 -1 (-6900 1250)(-6900 1200);
WIRE 16 -1 (-6900 1200)(-6725 1200);
WIRE 16 -1 (-6900 1200)(-6900 1150);
WIRE 16 -1 (-6725 1150)(-6900 1150);
WIRE 16 -1 (-6900 1150)(-6900 1100);
WIRE 16 -1 (-6900 1100)(-6725 1100);
WIRE 16 -1 (-6900 1100)(-6900 1050);
WIRE 16 -1 (-6900 1050)(-6725 1050);
WIRE 16 -1 (-6900 1050)(-6900 1000);
WIRE 16 -1 (-6900 1000)(-6725 1000);
WIRE 16 -1 (-6900 1000)(-6900 950);
WIRE 16 -1 (-6900 950)(-6725 950);
WIRE 16 -1 (-6900 950)(-6900 900);
WIRE 16 -1 (-6900 900)(-6725 900);
WIRE 16 -1 (-6900 900)(-6900 850);
WIRE 16 -1 (-6725 850)(-6900 850);
WIRE 16 -1 (-6900 850)(-6900 800);
WIRE 16 -1 (-6900 800)(-6725 800);
WIRE 16 -1 (-6900 800)(-6900 750);
WIRE 16 -1 (-6900 750)(-6725 750);
WIRE 16 -1 (-6900 750)(-6900 700);
WIRE 16 -1 (-6900 700)(-6725 700);
WIRE 16 -1 (-5425 6400)(-5275 6400);
WIRE 16 -1 (-5275 6400)(-5275 6350);
WIRE 16 -1 (-5275 6425)(-5275 6400);
WIRE 16 -1 (-5275 6350)(-5275 6300);
WIRE 16 -1 (-5275 6350)(-5425 6350);
WIRE 16 -1 (-5275 6250)(-5275 6300);
WIRE 16 -1 (-5425 6300)(-5275 6300);
WIRE 16 -1 (-5275 6250)(-5275 6200);
WIRE 16 -1 (-5425 6250)(-5275 6250);
WIRE 16 -1 (-5275 6200)(-5275 6150);
WIRE 16 -1 (-5425 6200)(-5275 6200);
WIRE 16 -1 (-5425 6150)(-5275 6150);
WIRE 16 -1 (-5275 6150)(-5275 6100);
WIRE 16 -1 (-5275 6100)(-5275 6050);
WIRE 16 -1 (-5425 6100)(-5275 6100);
WIRE 16 -1 (-5275 6000)(-5275 6050);
WIRE 16 -1 (-5425 6050)(-5275 6050);
WIRE 16 -1 (-5275 6000)(-5275 5950);
WIRE 16 -1 (-5425 6000)(-5275 6000);
WIRE 16 -1 (-5275 5950)(-5275 5900);
WIRE 16 -1 (-5425 5950)(-5275 5950);
WIRE 16 -1 (-5275 5850)(-5275 5900);
WIRE 16 -1 (-5425 5900)(-5275 5900);
WIRE 16 -1 (-5275 5850)(-5275 5800);
WIRE 16 -1 (-5425 5850)(-5275 5850);
WIRE 16 -1 (-5275 5800)(-5275 5750);
WIRE 16 -1 (-5425 5800)(-5275 5800);
WIRE 16 -1 (-5275 5700)(-5275 5750);
WIRE 16 -1 (-5425 5750)(-5275 5750);
WIRE 16 -1 (-5275 5700)(-5275 5650);
WIRE 16 -1 (-5425 5700)(-5275 5700);
WIRE 16 -1 (-5425 5650)(-5275 5650);
WIRE 16 -1 (-5275 5650)(-5275 5600);
WIRE 16 -1 (-5275 5600)(-5275 5550);
WIRE 16 -1 (-5425 5600)(-5275 5600);
WIRE 16 -1 (-5275 5550)(-5275 5500);
WIRE 16 -1 (-5425 5550)(-5275 5550);
WIRE 16 -1 (-5275 5450)(-5275 5500);
WIRE 16 -1 (-5425 5500)(-5275 5500);
WIRE 16 -1 (-5275 5450)(-5275 5400);
WIRE 16 -1 (-5425 5450)(-5275 5450);
WIRE 16 -1 (-5275 5400)(-5275 5350);
WIRE 16 -1 (-5425 5400)(-5275 5400);
WIRE 16 -1 (-5275 5350)(-5275 5300);
WIRE 16 -1 (-5425 5350)(-5275 5350);
WIRE 16 -1 (-5275 5300)(-5275 5250);
WIRE 16 -1 (-5425 5300)(-5275 5300);
WIRE 16 -1 (-5275 5200)(-5275 5250);
WIRE 16 -1 (-5425 5250)(-5275 5250);
WIRE 16 -1 (-5275 5200)(-5275 5150);
WIRE 16 -1 (-5425 5200)(-5275 5200);
WIRE 16 -1 (-5425 5150)(-5275 5150);
WIRE 16 -1 (-5275 5150)(-5275 5100);
WIRE 16 -1 (-5275 5100)(-5275 5050);
WIRE 16 -1 (-5425 5100)(-5275 5100);
WIRE 16 -1 (-5275 5050)(-5275 5000);
WIRE 16 -1 (-5425 5050)(-5275 5050);
WIRE 16 -1 (-5275 4950)(-5275 5000);
WIRE 16 -1 (-5425 5000)(-5275 5000);
WIRE 16 -1 (-5275 4950)(-5275 4900);
WIRE 16 -1 (-5425 4950)(-5275 4950);
WIRE 16 -1 (-5275 4900)(-5275 4850);
WIRE 16 -1 (-5425 4900)(-5275 4900);
WIRE 16 -1 (-5275 4800)(-5275 4850);
WIRE 16 -1 (-5425 4850)(-5275 4850);
WIRE 16 -1 (-5275 4800)(-5275 4750);
WIRE 16 -1 (-5425 4800)(-5275 4800);
WIRE 16 -1 (-5275 4750)(-5275 4700);
WIRE 16 -1 (-5425 4750)(-5275 4750);
WIRE 16 -1 (-5275 4650)(-5275 4700);
WIRE 16 -1 (-5425 4700)(-5275 4700);
WIRE 16 -1 (-5425 4650)(-5275 4650);
WIRE 16 -1 (-5275 4650)(-5275 4600);
WIRE 16 -1 (-5275 4600)(-5275 4550);
WIRE 16 -1 (-5425 4600)(-5275 4600);
WIRE 16 -1 (-5275 4550)(-5275 4500);
WIRE 16 -1 (-5425 4550)(-5275 4550);
WIRE 16 -1 (-5275 4500)(-5275 4450);
WIRE 16 -1 (-5425 4500)(-5275 4500);
WIRE 16 -1 (-5275 4400)(-5275 4450);
WIRE 16 -1 (-5425 4450)(-5275 4450);
WIRE 16 -1 (-5275 4400)(-5275 4350);
WIRE 16 -1 (-5425 4400)(-5275 4400);
WIRE 16 -1 (-5275 4350)(-5275 4300);
WIRE 16 -1 (-5425 4350)(-5275 4350);
WIRE 16 -1 (-5275 4300)(-5275 4250);
WIRE 16 -1 (-5425 4300)(-5275 4300);
WIRE 16 -1 (-5275 4250)(-5275 4200);
WIRE 16 -1 (-5425 4250)(-5275 4250);
WIRE 16 -1 (-5275 4150)(-5275 4200);
WIRE 16 -1 (-5425 4200)(-5275 4200);
WIRE 16 -1 (-5275 4150)(-5275 4100);
WIRE 16 -1 (-5425 4150)(-5275 4150);
WIRE 16 -1 (-5425 4100)(-5275 4100);
WIRE 16 -1 (-5275 4100)(-5275 4050);
WIRE 16 -1 (-5275 4050)(-5275 4000);
WIRE 16 -1 (-5425 4050)(-5275 4050);
WIRE 16 -1 (-5275 4000)(-5275 3950);
WIRE 16 -1 (-5425 4000)(-5275 4000);
WIRE 16 -1 (-5275 3900)(-5275 3950);
WIRE 16 -1 (-5425 3950)(-5275 3950);
WIRE 16 -1 (-5275 3900)(-5275 3850);
WIRE 16 -1 (-5425 3900)(-5275 3900);
WIRE 16 -1 (-5275 3850)(-5275 3800);
WIRE 16 -1 (-5425 3850)(-5275 3850);
WIRE 16 -1 (-5275 3750)(-5275 3800);
WIRE 16 -1 (-5425 3800)(-5275 3800);
WIRE 16 -1 (-5275 3750)(-5275 3700);
WIRE 16 -1 (-5425 3750)(-5275 3750);
WIRE 16 -1 (-5275 3700)(-5275 3650);
WIRE 16 -1 (-5425 3700)(-5275 3700);
WIRE 16 -1 (-5275 3600)(-5275 3650);
WIRE 16 -1 (-5425 3650)(-5275 3650);
WIRE 16 -1 (-5425 3600)(-5275 3600);
WIRE 16 -1 (-5275 3600)(-5275 3550);
WIRE 16 -1 (-5275 3550)(-5275 3500);
WIRE 16 -1 (-5425 3550)(-5275 3550);
WIRE 16 -1 (-5275 3500)(-5275 3450);
WIRE 16 -1 (-5425 3500)(-5275 3500);
WIRE 16 -1 (-5275 3450)(-5275 3400);
WIRE 16 -1 (-5425 3450)(-5275 3450);
WIRE 16 -1 (-5275 3350)(-5275 3400);
WIRE 16 -1 (-5425 3400)(-5275 3400);
WIRE 16 -1 (-5275 3350)(-5275 3300);
WIRE 16 -1 (-5425 3350)(-5275 3350);
WIRE 16 -1 (-5275 3300)(-5275 3250);
WIRE 16 -1 (-5425 3300)(-5275 3300);
WIRE 16 -1 (-5275 3250)(-5275 3200);
WIRE 16 -1 (-5425 3250)(-5275 3250);
WIRE 16 -1 (-5275 3200)(-5275 3150);
WIRE 16 -1 (-5425 3200)(-5275 3200);
WIRE 16 -1 (-5275 3100)(-5275 3150);
WIRE 16 -1 (-5425 3150)(-5275 3150);
WIRE 16 -1 (-5425 3100)(-5275 3100);
WIRE 16 -1 (-5275 3100)(-5275 3050);
WIRE 16 -1 (-5275 3050)(-5275 3000);
WIRE 16 -1 (-5425 3050)(-5275 3050);
WIRE 16 -1 (-5275 3000)(-5275 2950);
WIRE 16 -1 (-5425 3000)(-5275 3000);
WIRE 16 -1 (-5275 2950)(-5275 2900);
WIRE 16 -1 (-5425 2950)(-5275 2950);
WIRE 16 -1 (-5275 2850)(-5275 2900);
WIRE 16 -1 (-5425 2900)(-5275 2900);
WIRE 16 -1 (-5275 2850)(-5275 2800);
WIRE 16 -1 (-5425 2850)(-5275 2850);
WIRE 16 -1 (-5275 2800)(-5275 2750);
WIRE 16 -1 (-5425 2800)(-5275 2800);
WIRE 16 -1 (-5275 2700)(-5275 2750);
WIRE 16 -1 (-5425 2750)(-5275 2750);
WIRE 16 -1 (-5275 2700)(-5275 2650);
WIRE 16 -1 (-5425 2700)(-5275 2700);
WIRE 16 -1 (-5275 2650)(-5275 2600);
WIRE 16 -1 (-5425 2650)(-5275 2650);
WIRE 16 -1 (-5425 2600)(-5275 2600);
WIRE 16 -1 (-5275 2550)(-5275 2600);
WIRE 16 -1 (-5275 2550)(-5275 2500);
WIRE 16 -1 (-5425 2550)(-5275 2550);
WIRE 16 -1 (-5275 2500)(-5275 2450);
WIRE 16 -1 (-5425 2500)(-5275 2500);
WIRE 16 -1 (-5275 2450)(-5275 2400);
WIRE 16 -1 (-5425 2450)(-5275 2450);
WIRE 16 -1 (-5275 2400)(-5275 2350);
WIRE 16 -1 (-5425 2400)(-5275 2400);
WIRE 16 -1 (-5275 2300)(-5275 2350);
WIRE 16 -1 (-5425 2350)(-5275 2350);
WIRE 16 -1 (-5275 2300)(-5275 2250);
WIRE 16 -1 (-5425 2300)(-5275 2300);
WIRE 16 -1 (-5275 2250)(-5275 2200);
WIRE 16 -1 (-5425 2250)(-5275 2250);
WIRE 16 -1 (-5275 2200)(-5275 2150);
WIRE 16 -1 (-5425 2200)(-5275 2200);
WIRE 16 -1 (-5275 2150)(-5275 2100);
WIRE 16 -1 (-5425 2150)(-5275 2150);
WIRE 16 -1 (-5275 2050)(-5275 2100);
WIRE 16 -1 (-5425 2100)(-5275 2100);
WIRE 16 -1 (-5425 2050)(-5275 2050);
WIRE 16 -1 (-5275 2050)(-5275 2000);
WIRE 16 -1 (-5275 2000)(-5275 1950);
WIRE 16 -1 (-5425 2000)(-5275 2000);
WIRE 16 -1 (-5275 1950)(-5275 1900);
WIRE 16 -1 (-5425 1950)(-5275 1950);
WIRE 16 -1 (-5275 1900)(-5275 1850);
WIRE 16 -1 (-5425 1900)(-5275 1900);
WIRE 16 -1 (-5275 1800)(-5275 1850);
WIRE 16 -1 (-5425 1850)(-5275 1850);
WIRE 16 -1 (-5275 1800)(-5275 1750);
WIRE 16 -1 (-5425 1800)(-5275 1800);
WIRE 16 -1 (-5275 1750)(-5275 1700);
WIRE 16 -1 (-5425 1750)(-5275 1750);
WIRE 16 -1 (-5275 1650)(-5275 1700);
WIRE 16 -1 (-5425 1700)(-5275 1700);
WIRE 16 -1 (-5275 1650)(-5275 1600);
WIRE 16 -1 (-5425 1650)(-5275 1650);
WIRE 16 -1 (-5275 1600)(-5275 1550);
WIRE 16 -1 (-5425 1600)(-5275 1600);
WIRE 16 -1 (-5425 1550)(-5275 1550);
WIRE 16 -1 (-5275 1500)(-5275 1550);
WIRE 16 -1 (-5275 1500)(-5275 1450);
WIRE 16 -1 (-5425 1500)(-5275 1500);
WIRE 16 -1 (-5275 1450)(-5275 1400);
WIRE 16 -1 (-5425 1450)(-5275 1450);
WIRE 16 -1 (-5275 1400)(-5275 1350);
WIRE 16 -1 (-5425 1400)(-5275 1400);
WIRE 16 -1 (-5275 1350)(-5275 1300);
WIRE 16 -1 (-5425 1350)(-5275 1350);
WIRE 16 -1 (-5275 1250)(-5275 1300);
WIRE 16 -1 (-5425 1300)(-5275 1300);
WIRE 16 -1 (-5275 1250)(-5275 1200);
WIRE 16 -1 (-5425 1250)(-5275 1250);
WIRE 16 -1 (-5275 1200)(-5275 1150);
WIRE 16 -1 (-5425 1200)(-5275 1200);
WIRE 16 -1 (-5275 1150)(-5275 1100);
WIRE 16 -1 (-5425 1150)(-5275 1150);
WIRE 16 -1 (-5275 1100)(-5275 1050);
WIRE 16 -1 (-5425 1100)(-5275 1100);
WIRE 16 -1 (-5425 1050)(-5275 1050);
WIRE 16 -1 (-5275 1000)(-5275 1050);
WIRE 16 -1 (-5275 1000)(-5275 950);
WIRE 16 -1 (-5425 1000)(-5275 1000);
WIRE 16 -1 (-5275 950)(-5275 900);
WIRE 16 -1 (-5425 950)(-5275 950);
WIRE 16 -1 (-5275 900)(-5275 850);
WIRE 16 -1 (-5425 900)(-5275 900);
WIRE 16 -1 (-5275 850)(-5275 800);
WIRE 16 -1 (-5425 850)(-5275 850);
WIRE 16 -1 (-5275 750)(-5275 800);
WIRE 16 -1 (-5425 800)(-5275 800);
WIRE 16 -1 (-5275 750)(-5275 700);
WIRE 16 -1 (-5425 750)(-5275 750);
WIRE 16 -1 (-5275 700)(-5275 650);
WIRE 16 -1 (-5425 700)(-5275 700);
WIRE 16 -1 (-5275 600)(-5275 650);
WIRE 16 -1 (-5425 650)(-5275 650);
WIRE 16 -1 (-5275 600)(-5275 550);
WIRE 16 -1 (-5425 600)(-5275 600);
WIRE 16 -1 (-5425 550)(-5275 550);
WIRE 16 -1 (-5275 550)(-5275 500);
WIRE 16 -1 (-5275 450)(-5275 500);
WIRE 16 -1 (-5425 500)(-5275 500);
WIRE 16 -1 (-5275 450)(-5275 400);
WIRE 16 -1 (-5425 450)(-5275 450);
WIRE 16 -1 (-5275 400)(-5275 350);
WIRE 16 -1 (-5425 400)(-5275 400);
WIRE 16 -1 (-5275 350)(-5275 300);
WIRE 16 -1 (-5425 350)(-5275 350);
WIRE 16 -1 (-5275 300)(-5275 250);
WIRE 16 -1 (-5425 300)(-5275 300);
WIRE 16 -1 (-5425 250)(-5275 250);
WIRE 16 -1 (-4975 6025)(-4850 6025);
WIRE 16 -1 (-4975 6100)(-4975 6025);
WIRE 16 -1 (-4975 6025)(-4975 5975);
WIRE 16 -1 (-4975 5975)(-4850 5975);
WIRE 16 -1 (-4975 5975)(-4975 5925);
WIRE 16 -1 (-4975 5925)(-4850 5925);
WIRE 16 -1 (-4975 5925)(-4975 5875);
WIRE 16 -1 (-4975 5875)(-4850 5875);
WIRE 16 -1 (-4975 5875)(-4975 5825);
WIRE 16 -1 (-4975 5825)(-4850 5825);
WIRE 16 -1 (-4975 5825)(-4975 5775);
WIRE 16 -1 (-4975 5775)(-4850 5775);
WIRE 16 -1 (-4975 5775)(-4975 5725);
WIRE 16 -1 (-4975 5725)(-4850 5725);
WIRE 16 -1 (-4975 5725)(-4975 5675);
WIRE 16 -1 (-4975 5675)(-4850 5675);
WIRE 16 -1 (-4975 5675)(-4975 5625);
WIRE 16 -1 (-4850 5625)(-4975 5625);
WIRE 16 -1 (-4975 5625)(-4975 5575);
WIRE 16 -1 (-4975 5575)(-4850 5575);
WIRE 16 -1 (-4975 5575)(-4975 5525);
WIRE 16 -1 (-4975 5525)(-4850 5525);
WIRE 16 -1 (-4975 5525)(-4975 5475);
WIRE 16 -1 (-4975 5475)(-4850 5475);
WIRE 16 -1 (-4975 5475)(-4975 5425);
WIRE 16 -1 (-4975 5425)(-4850 5425);
WIRE 16 -1 (-4975 5425)(-4975 5375);
WIRE 16 -1 (-4975 5375)(-4850 5375);
WIRE 16 -1 (-4975 5375)(-4975 5325);
WIRE 16 -1 (-4975 5325)(-4850 5325);
WIRE 16 -1 (-4975 5325)(-4975 5275);
WIRE 16 -1 (-4975 5275)(-4850 5275);
WIRE 16 -1 (-4975 5275)(-4975 5225);
WIRE 16 -1 (-4975 5225)(-4850 5225);
WIRE 16 -1 (-4975 5225)(-4975 5175);
WIRE 16 -1 (-4975 5175)(-4850 5175);
WIRE 16 -1 (-4975 5175)(-4975 5125);
WIRE 16 -1 (-4975 5125)(-4850 5125);
WIRE 16 -1 (-4975 5125)(-4975 5075);
WIRE 16 -1 (-4850 5075)(-4975 5075);
WIRE 16 -1 (-4975 5075)(-4975 5025);
WIRE 16 -1 (-4975 5025)(-4850 5025);
WIRE 16 -1 (-4975 5025)(-4975 4975);
WIRE 16 -1 (-4975 4975)(-4850 4975);
WIRE 16 -1 (-4975 4975)(-4975 4925);
WIRE 16 -1 (-4975 4925)(-4850 4925);
WIRE 16 -1 (-4975 4925)(-4975 4875);
WIRE 16 -1 (-4975 4875)(-4850 4875);
WIRE 16 -1 (-4975 4875)(-4975 4825);
WIRE 16 -1 (-4975 4825)(-4850 4825);
WIRE 16 -1 (-4975 4825)(-4975 4775);
WIRE 16 -1 (-4975 4775)(-4850 4775);
WIRE 16 -1 (-4975 4775)(-4975 4725);
WIRE 16 -1 (-4975 4725)(-4850 4725);
WIRE 16 -1 (-4975 4725)(-4975 4675);
WIRE 16 -1 (-4975 4675)(-4850 4675);
WIRE 16 -1 (-4975 4675)(-4975 4625);
WIRE 16 -1 (-4975 4625)(-4850 4625);
WIRE 16 -1 (-4975 4625)(-4975 4575);
WIRE 16 -1 (-4850 4575)(-4975 4575);
WIRE 16 -1 (-4975 4575)(-4975 4525);
WIRE 16 -1 (-4975 4525)(-4850 4525);
WIRE 16 -1 (-4975 4525)(-4975 4475);
WIRE 16 -1 (-4975 4475)(-4850 4475);
WIRE 16 -1 (-4975 4475)(-4975 4425);
WIRE 16 -1 (-4975 4425)(-4850 4425);
WIRE 16 -1 (-4975 4425)(-4975 4375);
WIRE 16 -1 (-4975 4375)(-4850 4375);
WIRE 16 -1 (-4975 4375)(-4975 4325);
WIRE 16 -1 (-4975 4325)(-4850 4325);
WIRE 16 -1 (-4975 4325)(-4975 4275);
WIRE 16 -1 (-4975 4275)(-4850 4275);
WIRE 16 -1 (-4975 4275)(-4975 4225);
WIRE 16 -1 (-4975 4225)(-4850 4225);
WIRE 16 -1 (-4975 4225)(-4975 4175);
WIRE 16 -1 (-4975 4175)(-4850 4175);
WIRE 16 -1 (-4975 4175)(-4975 4125);
WIRE 16 -1 (-4975 4125)(-4850 4125);
WIRE 16 -1 (-4975 4125)(-4975 4075);
WIRE 16 -1 (-4850 4075)(-4975 4075);
WIRE 16 -1 (-4975 4075)(-4975 4025);
WIRE 16 -1 (-4975 4025)(-4850 4025);
WIRE 16 -1 (-4975 4025)(-4975 3975);
WIRE 16 -1 (-4975 3975)(-4850 3975);
WIRE 16 -1 (-4975 3975)(-4975 3925);
WIRE 16 -1 (-4975 3925)(-4850 3925);
WIRE 16 -1 (-4975 3925)(-4975 3875);
WIRE 16 -1 (-4975 3875)(-4850 3875);
WIRE 16 -1 (-4975 3875)(-4975 3825);
WIRE 16 -1 (-4975 3825)(-4850 3825);
WIRE 16 -1 (-4975 3825)(-4975 3775);
WIRE 16 -1 (-4975 3775)(-4850 3775);
WIRE 16 -1 (-4975 3775)(-4975 3725);
WIRE 16 -1 (-4975 3725)(-4850 3725);
WIRE 16 -1 (-4975 3725)(-4975 3675);
WIRE 16 -1 (-4975 3675)(-4850 3675);
WIRE 16 -1 (-4975 3675)(-4975 3625);
WIRE 16 -1 (-4975 3625)(-4850 3625);
WIRE 16 -1 (-4975 3625)(-4975 3575);
WIRE 16 -1 (-4850 3575)(-4975 3575);
WIRE 16 -1 (-4975 3575)(-4975 3525);
WIRE 16 -1 (-4975 3525)(-4850 3525);
WIRE 16 -1 (-4975 3525)(-4975 3475);
WIRE 16 -1 (-4975 3475)(-4850 3475);
WIRE 16 -1 (-4975 3475)(-4975 3425);
WIRE 16 -1 (-4975 3425)(-4850 3425);
WIRE 16 -1 (-4975 3425)(-4975 3375);
WIRE 16 -1 (-4975 3375)(-4850 3375);
WIRE 16 -1 (-4975 3375)(-4975 3325);
WIRE 16 -1 (-4975 3325)(-4850 3325);
WIRE 16 -1 (-4975 3325)(-4975 3275);
WIRE 16 -1 (-4975 3275)(-4850 3275);
WIRE 16 -1 (-4975 3275)(-4975 3225);
WIRE 16 -1 (-4975 3225)(-4850 3225);
WIRE 16 -1 (-4975 3225)(-4975 3175);
WIRE 16 -1 (-4975 3175)(-4850 3175);
WIRE 16 -1 (-4975 3175)(-4975 3125);
WIRE 16 -1 (-4975 3125)(-4850 3125);
WIRE 16 -1 (-4975 3125)(-4975 3075);
WIRE 16 -1 (-4975 3075)(-4850 3075);
WIRE 16 -1 (-3125 925)(-3475 925);
WIRE 16 -1 (-3475 1025)(-3475 925);
WIRE 16 -1 (-3475 875)(-3475 925);
WIRE 16 -1 (-3475 875)(-3125 875);
WIRE 16 -1 (-3125 2625)(-3475 2625);
WIRE 16 -1 (-3475 2775)(-3475 2625);
WIRE 16 -1 (-3475 2625)(-3475 2525);
WIRE 16 -1 (-3475 2525)(-3125 2525);
WIRE 16 -1 (-3475 2525)(-3475 2475);
WIRE 16 -1 (-3475 2475)(-3125 2475);
WIRE 16 -1 (-3475 2475)(-3475 2425);
WIRE 16 -1 (-3475 2425)(-3125 2425);
WIRE 16 -1 (-3475 2425)(-3475 2375);
WIRE 16 -1 (-3475 2375)(-3125 2375);
WIRE 16 -1 (-3475 2375)(-3475 2325);
WIRE 16 -1 (-3475 2325)(-3125 2325);
WIRE 16 -1 (-3475 2325)(-3475 2275);
WIRE 16 -1 (-3475 2275)(-3125 2275);
WIRE 16 -1 (-3475 2275)(-3475 2225);
WIRE 16 -1 (-3475 2225)(-3125 2225);
WIRE 16 -1 (-3475 2225)(-3475 2175);
WIRE 16 -1 (-3475 2175)(-3125 2175);
WIRE 16 -1 (-3475 2175)(-3475 2125);
WIRE 16 -1 (-3475 2125)(-3125 2125);
WIRE 16 -1 (-3475 2125)(-3475 2075);
WIRE 16 -1 (-3475 2075)(-3125 2075);
WIRE 16 -1 (-3475 2075)(-3475 2025);
WIRE 16 -1 (-3125 2025)(-3475 2025);
WIRE 16 -1 (-3475 2025)(-3475 1975);
WIRE 16 -1 (-3475 1975)(-3125 1975);
WIRE 16 -1 (-3475 1975)(-3475 1925);
WIRE 16 -1 (-3475 1925)(-3125 1925);
WIRE 16 -1 (-3475 1925)(-3475 1875);
WIRE 16 -1 (-3475 1875)(-3125 1875);
WIRE 16 -1 (-3475 1875)(-3475 1825);
WIRE 16 -1 (-3475 1825)(-3125 1825);
WIRE 16 -1 (-3475 1825)(-3475 1775);
WIRE 16 -1 (-3475 1775)(-3125 1775);
WIRE 16 -1 (-3475 1775)(-3475 1725);
WIRE 16 -1 (-3475 1725)(-3125 1725);
WIRE 16 -1 (-3475 1725)(-3475 1675);
WIRE 16 -1 (-3475 1675)(-3125 1675);
WIRE 16 -1 (-3475 1675)(-3475 1625);
WIRE 16 -1 (-3475 1625)(-3125 1625);
WIRE 16 -1 (-3475 1625)(-3475 1575);
WIRE 16 -1 (-3475 1575)(-3125 1575);
WIRE 16 -1 (-3475 1575)(-3475 1525);
WIRE 16 -1 (-3125 1525)(-3475 1525);
WIRE 16 -1 (-3475 1525)(-3475 1175);
WIRE 16 -1 (-3475 1175)(-3125 1175);
WIRE 16 -1 (-3300 6525)(-3125 6525);
WIRE 16 -1 (-3300 6550)(-3300 6525);
WIRE 16 -1 (-3300 6525)(-3300 6475);
WIRE 16 -1 (-3300 6475)(-3125 6475);
WIRE 16 -1 (-3300 6475)(-3300 6425);
WIRE 16 -1 (-3300 6425)(-3125 6425);
WIRE 16 -1 (-3300 6425)(-3300 6375);
WIRE 16 -1 (-3125 6375)(-3300 6375);
WIRE 16 -1 (-3300 6375)(-3300 6325);
WIRE 16 -1 (-3300 6325)(-3125 6325);
WIRE 16 -1 (-3300 6325)(-3300 6275);
WIRE 16 -1 (-3300 6275)(-3125 6275);
WIRE 16 -1 (-3300 6275)(-3300 6225);
WIRE 16 -1 (-3300 6225)(-3125 6225);
WIRE 16 -1 (-3300 6225)(-3300 6175);
WIRE 16 -1 (-3300 6175)(-3125 6175);
WIRE 16 -1 (-3300 6175)(-3300 6125);
WIRE 16 -1 (-3125 6125)(-3300 6125);
WIRE 16 -1 (-3300 6125)(-3300 6075);
WIRE 16 -1 (-3300 6075)(-3125 6075);
WIRE 16 -1 (-3300 6075)(-3300 6025);
WIRE 16 -1 (-3300 6025)(-3125 6025);
WIRE 16 -1 (-3300 6025)(-3300 5975);
WIRE 16 -1 (-3300 5975)(-3125 5975);
WIRE 16 -1 (-3300 5975)(-3300 5925);
WIRE 16 -1 (-3300 5925)(-3125 5925);
WIRE 16 -1 (-3300 5925)(-3300 5875);
WIRE 16 -1 (-3125 5875)(-3300 5875);
WIRE 16 -1 (-3300 5875)(-3300 5825);
WIRE 16 -1 (-3300 5825)(-3125 5825);
WIRE 16 -1 (-3300 5825)(-3300 5775);
WIRE 16 -1 (-3300 5775)(-3125 5775);
WIRE 16 -1 (-3300 5775)(-3300 5725);
WIRE 16 -1 (-3300 5725)(-3125 5725);
WIRE 16 -1 (-3300 5725)(-3300 5675);
WIRE 16 -1 (-3300 5675)(-3125 5675);
WIRE 16 -1 (-3300 5675)(-3300 5625);
WIRE 16 -1 (-3125 5625)(-3300 5625);
WIRE 16 -1 (-3300 5625)(-3300 5575);
WIRE 16 -1 (-3300 5575)(-3125 5575);
WIRE 16 -1 (-3300 5575)(-3300 5525);
WIRE 16 -1 (-3300 5525)(-3125 5525);
WIRE 16 -1 (-3300 5525)(-3300 5475);
WIRE 16 -1 (-3300 5475)(-3125 5475);
WIRE 16 -1 (-3300 5475)(-3300 5425);
WIRE 16 -1 (-3300 5425)(-3125 5425);
WIRE 16 -1 (-3300 5425)(-3300 5375);
WIRE 16 -1 (-3125 5375)(-3300 5375);
WIRE 16 -1 (-3300 5375)(-3300 5325);
WIRE 16 -1 (-3300 5325)(-3125 5325);
WIRE 16 -1 (-3300 5325)(-3300 5275);
WIRE 16 -1 (-3300 5275)(-3125 5275);
WIRE 16 -1 (-3300 5275)(-3300 5225);
WIRE 16 -1 (-3300 5225)(-3125 5225);
WIRE 16 -1 (-3300 5225)(-3300 5175);
WIRE 16 -1 (-3300 5175)(-3125 5175);
WIRE 16 -1 (-3300 5175)(-3300 5125);
WIRE 16 -1 (-3300 5125)(-3125 5125);
WIRE 16 -1 (-3300 5125)(-3300 5075);
WIRE 16 -1 (-3125 5075)(-3300 5075);
WIRE 16 -1 (-3300 5075)(-3300 5025);
WIRE 16 -1 (-3300 5025)(-3125 5025);
WIRE 16 -1 (-3300 5025)(-3300 4975);
WIRE 16 -1 (-3300 4975)(-3125 4975);
WIRE 16 -1 (-3300 4975)(-3300 4925);
WIRE 16 -1 (-3300 4925)(-3125 4925);
WIRE 16 -1 (-3300 4925)(-3300 4875);
WIRE 16 -1 (-3300 4875)(-3125 4875);
WIRE 16 -1 (-3300 4875)(-3300 4825);
WIRE 16 -1 (-3125 4825)(-3300 4825);
WIRE 16 -1 (-3300 4825)(-3300 4775);
WIRE 16 -1 (-3300 4775)(-3125 4775);
WIRE 16 -1 (-3300 4775)(-3300 4725);
WIRE 16 -1 (-3300 4725)(-3125 4725);
WIRE 16 -1 (-3300 4725)(-3300 4675);
WIRE 16 -1 (-3300 4675)(-3125 4675);
WIRE 16 -1 (-3300 4675)(-3300 4625);
WIRE 16 -1 (-3300 4625)(-3125 4625);
WIRE 16 -1 (-3300 4625)(-3300 4575);
WIRE 16 -1 (-3125 4575)(-3300 4575);
WIRE 16 -1 (-3300 4575)(-3300 4525);
WIRE 16 -1 (-3300 4525)(-3125 4525);
WIRE 16 -1 (-3300 4525)(-3300 4475);
WIRE 16 -1 (-3300 4475)(-3125 4475);
WIRE 16 -1 (-3300 4475)(-3300 4425);
WIRE 16 -1 (-3300 4425)(-3125 4425);
WIRE 16 -1 (-3300 4425)(-3300 4375);
WIRE 16 -1 (-3300 4375)(-3125 4375);
WIRE 16 -1 (-3300 4375)(-3300 4325);
WIRE 16 -1 (-3125 4325)(-3300 4325);
WIRE 16 -1 (-3300 4325)(-3300 4275);
WIRE 16 -1 (-3300 4275)(-3125 4275);
WIRE 16 -1 (-3300 4275)(-3300 4225);
WIRE 16 -1 (-3300 4225)(-3125 4225);
WIRE 16 -1 (-3300 4225)(-3300 4175);
WIRE 16 -1 (-3300 4175)(-3125 4175);
WIRE 16 -1 (-3300 4175)(-3300 4125);
WIRE 16 -1 (-3300 4125)(-3125 4125);
WIRE 16 -1 (-3300 4125)(-3300 4075);
WIRE 16 -1 (-3125 4075)(-3300 4075);
WIRE 16 -1 (-3300 4075)(-3300 4025);
WIRE 16 -1 (-3300 4025)(-3125 4025);
WIRE 16 -1 (-3300 4025)(-3300 3975);
WIRE 16 -1 (-3300 3975)(-3125 3975);
WIRE 16 -1 (-3300 3975)(-3300 3925);
WIRE 16 -1 (-3300 3925)(-3125 3925);
WIRE 16 -1 (-3300 3925)(-3300 3875);
WIRE 16 -1 (-3300 3875)(-3125 3875);
WIRE 16 -1 (-3300 3875)(-3300 3825);
WIRE 16 -1 (-3125 3825)(-3300 3825);
WIRE 16 -1 (-3300 3825)(-3300 3775);
WIRE 16 -1 (-3300 3775)(-3125 3775);
WIRE 16 -1 (-3300 3775)(-3300 3725);
WIRE 16 -1 (-3300 3725)(-3125 3725);
WIRE 16 -1 (-3300 3725)(-3300 3675);
WIRE 16 -1 (-3300 3675)(-3125 3675);
WIRE 16 -1 (-3300 3675)(-3300 3625);
WIRE 16 -1 (-3300 3625)(-3125 3625);
WIRE 16 -1 (-3300 3625)(-3300 3575);
WIRE 16 -1 (-3125 3575)(-3300 3575);
WIRE 16 -1 (-3300 3575)(-3300 3525);
WIRE 16 -1 (-3300 3525)(-3125 3525);
WIRE 16 -1 (-3300 3525)(-3300 3475);
WIRE 16 -1 (-3300 3475)(-3125 3475);
WIRE 16 -1 (-3300 3475)(-3300 3425);
WIRE 16 -1 (-3300 3425)(-3125 3425);
WIRE 16 -1 (-3300 3425)(-3300 3375);
WIRE 16 -1 (-3300 3375)(-3125 3375);
WIRE 16 -1 (-3300 3375)(-3300 3325);
WIRE 16 -1 (-3125 3325)(-3300 3325);
WIRE 16 -1 (-3300 3325)(-3300 3275);
WIRE 16 -1 (-3300 3275)(-3125 3275);
WIRE 16 -1 (-3300 3275)(-3300 3225);
WIRE 16 -1 (-3300 3225)(-3125 3225);
WIRE 16 -1 (-3300 3225)(-3300 3175);
WIRE 16 -1 (-3300 3175)(-3125 3175);
WIRE 16 -1 (-3300 3175)(-3300 3125);
WIRE 16 -1 (-3300 3125)(-3125 3125);
WIRE 16 -1 (-3300 3125)(-3300 3075);
WIRE 16 -1 (-3300 3075)(-3125 3075);
WIRE 16 -1 (-3300 3075)(-3300 3025);
WIRE 16 -1 (-3125 3025)(-3300 3025);
WIRE 16 -1 (-3300 3025)(-3300 2975);
WIRE 16 -1 (-3300 2975)(-3125 2975);
WIRE 16 -1 (-3300 2975)(-3300 2925);
WIRE 16 -1 (-3300 2925)(-3125 2925);
WIRE 16 -1 (-3300 2925)(-3300 2875);
WIRE 16 -1 (-3300 2875)(-3125 2875);
WIRE 16 -1 (-3300 2875)(-3300 2825);
WIRE 16 -1 (-3300 2825)(-3125 2825);
WIRE 16 -1 (-3300 2825)(-3300 2775);
WIRE 16 -1 (-3125 2775)(-3300 2775);
WIRE 16 -1 (-3300 2775)(-3300 2725);
WIRE 16 -1 (-3300 2725)(-3125 2725);
WIRE 16 -1 (-3650 5975)(-3500 5975);
WIRE 16 -1 (-3500 6025)(-3500 5975);
WIRE 16 -1 (-3500 5975)(-3500 5925);
WIRE 16 -1 (-3500 5925)(-3500 5875);
WIRE 16 -1 (-3650 5925)(-3500 5925);
WIRE 16 -1 (-3650 6025)(-3500 6025);
WIRE 16 -1 (-3500 6025)(-3500 6100);
WIRE 16 -1 (-3500 5875)(-3500 5825);
WIRE 16 -1 (-3650 5875)(-3500 5875);
WIRE 16 -1 (-3500 5825)(-3500 5775);
WIRE 16 -1 (-3650 5825)(-3500 5825);
WIRE 16 -1 (-3500 5775)(-3500 5725);
WIRE 16 -1 (-3650 5775)(-3500 5775);
WIRE 16 -1 (-3500 5725)(-3500 5675);
WIRE 16 -1 (-3650 5725)(-3500 5725);
WIRE 16 -1 (-3500 5675)(-3500 5625);
WIRE 16 -1 (-3650 5675)(-3500 5675);
WIRE 16 -1 (-3500 5625)(-3500 5575);
WIRE 16 -1 (-3650 5625)(-3500 5625);
WIRE 16 -1 (-3500 5575)(-3500 5525);
WIRE 16 -1 (-3650 5575)(-3500 5575);
WIRE 16 -1 (-3500 5525)(-3500 5475);
WIRE 16 -1 (-3650 5525)(-3500 5525);
WIRE 16 -1 (-3500 5475)(-3500 5425);
WIRE 16 -1 (-3650 5475)(-3500 5475);
WIRE 16 -1 (-3500 5425)(-3500 5375);
WIRE 16 -1 (-3650 5425)(-3500 5425);
WIRE 16 -1 (-3500 5375)(-3500 5325);
WIRE 16 -1 (-3650 5375)(-3500 5375);
WIRE 16 -1 (-3500 5325)(-3500 5275);
WIRE 16 -1 (-3650 5325)(-3500 5325);
WIRE 16 -1 (-3500 5275)(-3500 5225);
WIRE 16 -1 (-3650 5275)(-3500 5275);
WIRE 16 -1 (-3500 5225)(-3500 5175);
WIRE 16 -1 (-3650 5225)(-3500 5225);
WIRE 16 -1 (-3500 5175)(-3500 5125);
WIRE 16 -1 (-3650 5175)(-3500 5175);
WIRE 16 -1 (-3650 5125)(-3500 5125);
WIRE 16 -1 (-3500 5125)(-3500 5075);
WIRE 16 -1 (-3500 5075)(-3500 5025);
WIRE 16 -1 (-3650 5075)(-3500 5075);
WIRE 16 -1 (-3500 5025)(-3500 4975);
WIRE 16 -1 (-3650 5025)(-3500 5025);
WIRE 16 -1 (-3500 4975)(-3500 4925);
WIRE 16 -1 (-3650 4975)(-3500 4975);
WIRE 16 -1 (-3500 4925)(-3500 4875);
WIRE 16 -1 (-3650 4925)(-3500 4925);
WIRE 16 -1 (-3500 4875)(-3500 4825);
WIRE 16 -1 (-3650 4875)(-3500 4875);
WIRE 16 -1 (-3500 4825)(-3500 4775);
WIRE 16 -1 (-3650 4825)(-3500 4825);
WIRE 16 -1 (-3500 4775)(-3500 4725);
WIRE 16 -1 (-3650 4775)(-3500 4775);
WIRE 16 -1 (-3500 4725)(-3500 4675);
WIRE 16 -1 (-3650 4725)(-3500 4725);
WIRE 16 -1 (-3500 4675)(-3500 4625);
WIRE 16 -1 (-3650 4675)(-3500 4675);
WIRE 16 -1 (-3500 4625)(-3500 4575);
WIRE 16 -1 (-3650 4625)(-3500 4625);
WIRE 16 -1 (-3500 4575)(-3500 4525);
WIRE 16 -1 (-3650 4575)(-3500 4575);
WIRE 16 -1 (-3500 4525)(-3500 4475);
WIRE 16 -1 (-3650 4525)(-3500 4525);
WIRE 16 -1 (-3500 4475)(-3500 4425);
WIRE 16 -1 (-3650 4475)(-3500 4475);
WIRE 16 -1 (-3500 4425)(-3500 4375);
WIRE 16 -1 (-3650 4425)(-3500 4425);
WIRE 16 -1 (-3500 4375)(-3500 4325);
WIRE 16 -1 (-3650 4375)(-3500 4375);
WIRE 16 -1 (-3500 4325)(-3500 4275);
WIRE 16 -1 (-3650 4325)(-3500 4325);
WIRE 16 -1 (-3500 4275)(-3500 4225);
WIRE 16 -1 (-3650 4275)(-3500 4275);
WIRE 16 -1 (-3500 4225)(-3500 4175);
WIRE 16 -1 (-3650 4225)(-3500 4225);
WIRE 16 -1 (-3500 4175)(-3500 4125);
WIRE 16 -1 (-3650 4175)(-3500 4175);
WIRE 16 -1 (-3650 4125)(-3500 4125);
WIRE 16 -1 (-3500 4125)(-3500 4075);
WIRE 16 -1 (-3500 4075)(-3500 4025);
WIRE 16 -1 (-3650 4075)(-3500 4075);
WIRE 16 -1 (-3500 4025)(-3500 3975);
WIRE 16 -1 (-3650 4025)(-3500 4025);
WIRE 16 -1 (-3500 3975)(-3500 3925);
WIRE 16 -1 (-3650 3975)(-3500 3975);
WIRE 16 -1 (-3500 3925)(-3500 3875);
WIRE 16 -1 (-3650 3925)(-3500 3925);
WIRE 16 -1 (-3500 3875)(-3500 3825);
WIRE 16 -1 (-3650 3875)(-3500 3875);
WIRE 16 -1 (-3500 3825)(-3500 3775);
WIRE 16 -1 (-3650 3825)(-3500 3825);
WIRE 16 -1 (-3500 3775)(-3500 3725);
WIRE 16 -1 (-3650 3775)(-3500 3775);
WIRE 16 -1 (-3500 3725)(-3500 3675);
WIRE 16 -1 (-3650 3725)(-3500 3725);
WIRE 16 -1 (-3500 3675)(-3500 3625);
WIRE 16 -1 (-3650 3675)(-3500 3675);
WIRE 16 -1 (-3500 3625)(-3500 3575);
WIRE 16 -1 (-3650 3625)(-3500 3625);
WIRE 16 -1 (-3500 3575)(-3500 3525);
WIRE 16 -1 (-3650 3575)(-3500 3575);
WIRE 16 -1 (-3500 3525)(-3500 3475);
WIRE 16 -1 (-3650 3525)(-3500 3525);
WIRE 16 -1 (-3650 3475)(-3500 3475);
WIRE 16 -1 (-1825 6525)(-1675 6525);
WIRE 16 -1 (-1675 6575)(-1675 6525);
WIRE 16 -1 (-1675 6525)(-1675 6475);
WIRE 16 -1 (-1675 6475)(-1675 6425);
WIRE 16 -1 (-1825 6475)(-1675 6475);
WIRE 16 -1 (-1675 6425)(-1675 6375);
WIRE 16 -1 (-1825 6425)(-1675 6425);
WIRE 16 -1 (-1675 6375)(-1675 6325);
WIRE 16 -1 (-1825 6375)(-1675 6375);
WIRE 16 -1 (-1675 6325)(-1675 6275);
WIRE 16 -1 (-1825 6325)(-1675 6325);
WIRE 16 -1 (-1675 6275)(-1675 6225);
WIRE 16 -1 (-1825 6275)(-1675 6275);
WIRE 16 -1 (-1675 6225)(-1675 6175);
WIRE 16 -1 (-1825 6225)(-1675 6225);
WIRE 16 -1 (-1825 6175)(-1675 6175);
WIRE 16 -1 (-1675 6175)(-1675 6125);
WIRE 16 -1 (-1675 6125)(-1675 6075);
WIRE 16 -1 (-1825 6125)(-1675 6125);
WIRE 16 -1 (-1675 6075)(-1675 6025);
WIRE 16 -1 (-1825 6075)(-1675 6075);
WIRE 16 -1 (-1675 6025)(-1675 5975);
WIRE 16 -1 (-1825 6025)(-1675 6025);
WIRE 16 -1 (-1675 5975)(-1675 5925);
WIRE 16 -1 (-1825 5975)(-1675 5975);
WIRE 16 -1 (-1675 5925)(-1675 5875);
WIRE 16 -1 (-1825 5925)(-1675 5925);
WIRE 16 -1 (-1675 5875)(-1675 5825);
WIRE 16 -1 (-1825 5875)(-1675 5875);
WIRE 16 -1 (-1675 5825)(-1675 5775);
WIRE 16 -1 (-1825 5825)(-1675 5825);
WIRE 16 -1 (-1675 5775)(-1675 5725);
WIRE 16 -1 (-1825 5775)(-1675 5775);
WIRE 16 -1 (-1675 5725)(-1675 5675);
WIRE 16 -1 (-1675 5725)(-1825 5725);
WIRE 16 -1 (-1825 5675)(-1675 5675);
WIRE 16 -1 (-1675 5675)(-1675 5625);
WIRE 16 -1 (-1675 5625)(-1675 5575);
WIRE 16 -1 (-1825 5625)(-1675 5625);
WIRE 16 -1 (-1675 5575)(-1675 5525);
WIRE 16 -1 (-1825 5575)(-1675 5575);
WIRE 16 -1 (-1675 5525)(-1675 5475);
WIRE 16 -1 (-1825 5525)(-1675 5525);
WIRE 16 -1 (-1675 5475)(-1675 5425);
WIRE 16 -1 (-1825 5475)(-1675 5475);
WIRE 16 -1 (-1675 5425)(-1675 5375);
WIRE 16 -1 (-1825 5425)(-1675 5425);
WIRE 16 -1 (-1675 5375)(-1675 5325);
WIRE 16 -1 (-1825 5375)(-1675 5375);
WIRE 16 -1 (-1675 5325)(-1675 5275);
WIRE 16 -1 (-1825 5325)(-1675 5325);
WIRE 16 -1 (-1675 5275)(-1675 5225);
WIRE 16 -1 (-1825 5275)(-1675 5275);
WIRE 16 -1 (-1675 5225)(-1675 5175);
WIRE 16 -1 (-1825 5225)(-1675 5225);
WIRE 16 -1 (-1675 5175)(-1675 5125);
WIRE 16 -1 (-1825 5175)(-1675 5175);
WIRE 16 -1 (-1825 5125)(-1675 5125);
WIRE 16 -1 (-1675 5125)(-1675 5075);
WIRE 16 -1 (-1675 5075)(-1675 5025);
WIRE 16 -1 (-1825 5075)(-1675 5075);
WIRE 16 -1 (-1675 5025)(-1675 4975);
WIRE 16 -1 (-1825 5025)(-1675 5025);
WIRE 16 -1 (-1675 4975)(-1675 4925);
WIRE 16 -1 (-1825 4975)(-1675 4975);
WIRE 16 -1 (-1675 4925)(-1675 4875);
WIRE 16 -1 (-1825 4925)(-1675 4925);
WIRE 16 -1 (-1675 4875)(-1675 4825);
WIRE 16 -1 (-1825 4875)(-1675 4875);
WIRE 16 -1 (-1675 4825)(-1675 4775);
WIRE 16 -1 (-1825 4825)(-1675 4825);
WIRE 16 -1 (-1675 4775)(-1675 4725);
WIRE 16 -1 (-1825 4775)(-1675 4775);
WIRE 16 -1 (-1675 4725)(-1675 4675);
WIRE 16 -1 (-1825 4725)(-1675 4725);
WIRE 16 -1 (-1675 4675)(-1675 4625);
WIRE 16 -1 (-1825 4675)(-1675 4675);
WIRE 16 -1 (-1825 4625)(-1675 4625);
WIRE 16 -1 (-1675 4625)(-1675 4575);
WIRE 16 -1 (-1675 4575)(-1675 4525);
WIRE 16 -1 (-1825 4575)(-1675 4575);
WIRE 16 -1 (-1675 4525)(-1675 4475);
WIRE 16 -1 (-1825 4525)(-1675 4525);
WIRE 16 -1 (-1675 4475)(-1675 4425);
WIRE 16 -1 (-1825 4475)(-1675 4475);
WIRE 16 -1 (-1675 4425)(-1675 4375);
WIRE 16 -1 (-1825 4425)(-1675 4425);
WIRE 16 -1 (-1675 4375)(-1675 4325);
WIRE 16 -1 (-1825 4375)(-1675 4375);
WIRE 16 -1 (-1675 4325)(-1675 4275);
WIRE 16 -1 (-1825 4325)(-1675 4325);
WIRE 16 -1 (-1675 4275)(-1675 4225);
WIRE 16 -1 (-1825 4275)(-1675 4275);
WIRE 16 -1 (-1675 4225)(-1675 4175);
WIRE 16 -1 (-1825 4225)(-1675 4225);
WIRE 16 -1 (-1675 4175)(-1675 4125);
WIRE 16 -1 (-1825 4175)(-1675 4175);
WIRE 16 -1 (-1825 4125)(-1675 4125);
WIRE 16 -1 (-1675 4125)(-1675 4075);
WIRE 16 -1 (-1675 4075)(-1675 4025);
WIRE 16 -1 (-1825 4075)(-1675 4075);
WIRE 16 -1 (-1675 4025)(-1675 3975);
WIRE 16 -1 (-1825 4025)(-1675 4025);
WIRE 16 -1 (-1675 3975)(-1675 3925);
WIRE 16 -1 (-1825 3975)(-1675 3975);
WIRE 16 -1 (-1675 3925)(-1675 3875);
WIRE 16 -1 (-1825 3925)(-1675 3925);
WIRE 16 -1 (-1675 3875)(-1675 3825);
WIRE 16 -1 (-1825 3875)(-1675 3875);
WIRE 16 -1 (-1675 3825)(-1675 3775);
WIRE 16 -1 (-1825 3825)(-1675 3825);
WIRE 16 -1 (-1675 3775)(-1675 3725);
WIRE 16 -1 (-1825 3775)(-1675 3775);
WIRE 16 -1 (-1675 3725)(-1675 3675);
WIRE 16 -1 (-1825 3725)(-1675 3725);
WIRE 16 -1 (-1675 3675)(-1675 3625);
WIRE 16 -1 (-1825 3675)(-1675 3675);
WIRE 16 -1 (-1825 3625)(-1675 3625);
WIRE 16 -1 (-1675 3625)(-1675 3575);
WIRE 16 -1 (-1675 3575)(-1675 3525);
WIRE 16 -1 (-1825 3575)(-1675 3575);
WIRE 16 -1 (-1675 3525)(-1675 3475);
WIRE 16 -1 (-1825 3525)(-1675 3525);
WIRE 16 -1 (-1675 3475)(-1675 3425);
WIRE 16 -1 (-1825 3475)(-1675 3475);
WIRE 16 -1 (-1675 3425)(-1675 3375);
WIRE 16 -1 (-1825 3425)(-1675 3425);
WIRE 16 -1 (-1675 3375)(-1675 3325);
WIRE 16 -1 (-1825 3375)(-1675 3375);
WIRE 16 -1 (-1675 3325)(-1675 3275);
WIRE 16 -1 (-1825 3325)(-1675 3325);
WIRE 16 -1 (-1675 3275)(-1675 3225);
WIRE 16 -1 (-1825 3275)(-1675 3275);
WIRE 16 -1 (-1675 3225)(-1675 3175);
WIRE 16 -1 (-1825 3225)(-1675 3225);
WIRE 16 -1 (-1675 3175)(-1675 3125);
WIRE 16 -1 (-1825 3175)(-1675 3175);
WIRE 16 -1 (-1675 3125)(-1675 3075);
WIRE 16 -1 (-1825 3125)(-1675 3125);
WIRE 16 -1 (-1825 3075)(-1675 3075);
WIRE 16 -1 (-1675 3075)(-1675 3025);
WIRE 16 -1 (-1675 3025)(-1675 2975);
WIRE 16 -1 (-1825 3025)(-1675 3025);
WIRE 16 -1 (-1675 2975)(-1675 2925);
WIRE 16 -1 (-1825 2975)(-1675 2975);
WIRE 16 -1 (-1675 2925)(-1675 2875);
WIRE 16 -1 (-1825 2925)(-1675 2925);
WIRE 16 -1 (-1675 2875)(-1675 2825);
WIRE 16 -1 (-1825 2875)(-1675 2875);
WIRE 16 -1 (-1675 2825)(-1675 2775);
WIRE 16 -1 (-1825 2825)(-1675 2825);
WIRE 16 -1 (-1675 2775)(-1675 2725);
WIRE 16 -1 (-1825 2775)(-1675 2775);
WIRE 16 -1 (-1675 2725)(-1675 2675);
WIRE 16 -1 (-1825 2725)(-1675 2725);
WIRE 16 -1 (-1675 2675)(-1675 2625);
WIRE 16 -1 (-1825 2675)(-1675 2675);
WIRE 16 -1 (-1675 2625)(-1675 2575);
WIRE 16 -1 (-1825 2625)(-1675 2625);
WIRE 16 -1 (-1825 2575)(-1675 2575);
WIRE 16 -1 (-1675 2575)(-1675 2525);
WIRE 16 -1 (-1675 2525)(-1675 2475);
WIRE 16 -1 (-1825 2525)(-1675 2525);
WIRE 16 -1 (-1675 2475)(-1675 2425);
WIRE 16 -1 (-1825 2475)(-1675 2475);
WIRE 16 -1 (-1675 2425)(-1675 2375);
WIRE 16 -1 (-1825 2425)(-1675 2425);
WIRE 16 -1 (-1675 2375)(-1675 2325);
WIRE 16 -1 (-1825 2375)(-1675 2375);
WIRE 16 -1 (-1675 2325)(-1675 2275);
WIRE 16 -1 (-1825 2325)(-1675 2325);
WIRE 16 -1 (-1675 2275)(-1675 2225);
WIRE 16 -1 (-1825 2275)(-1675 2275);
WIRE 16 -1 (-1675 2225)(-1675 2175);
WIRE 16 -1 (-1825 2225)(-1675 2225);
WIRE 16 -1 (-1675 2175)(-1675 2125);
WIRE 16 -1 (-1825 2175)(-1675 2175);
WIRE 16 -1 (-1675 2125)(-1675 2075);
WIRE 16 -1 (-1825 2125)(-1675 2125);
WIRE 16 -1 (-1825 2075)(-1675 2075);
WIRE 16 -1 (-1675 2075)(-1675 2025);
WIRE 16 -1 (-1675 2025)(-1675 1975);
WIRE 16 -1 (-1825 2025)(-1675 2025);
WIRE 16 -1 (-1675 1975)(-1675 1925);
WIRE 16 -1 (-1825 1975)(-1675 1975);
WIRE 16 -1 (-1675 1925)(-1675 1875);
WIRE 16 -1 (-1825 1925)(-1675 1925);
WIRE 16 -1 (-1675 1875)(-1675 1825);
WIRE 16 -1 (-1825 1875)(-1675 1875);
WIRE 16 -1 (-1675 1825)(-1675 1775);
WIRE 16 -1 (-1825 1825)(-1675 1825);
WIRE 16 -1 (-1675 1775)(-1675 1725);
WIRE 16 -1 (-1825 1775)(-1675 1775);
WIRE 16 -1 (-1675 1725)(-1675 1675);
WIRE 16 -1 (-1825 1725)(-1675 1725);
WIRE 16 -1 (-1675 1675)(-1675 1625);
WIRE 16 -1 (-1825 1675)(-1675 1675);
WIRE 16 -1 (-1675 1625)(-1675 1575);
WIRE 16 -1 (-1825 1625)(-1675 1625);
WIRE 16 -1 (-1825 1575)(-1675 1575);
WIRE 16 -1 (-1675 1575)(-1675 1525);
WIRE 16 -1 (-1675 1525)(-1675 1475);
WIRE 16 -1 (-1825 1525)(-1675 1525);
WIRE 16 -1 (-1675 1475)(-1675 1425);
WIRE 16 -1 (-1825 1475)(-1675 1475);
WIRE 16 -1 (-1675 1425)(-1675 1375);
WIRE 16 -1 (-1825 1425)(-1675 1425);
WIRE 16 -1 (-1675 1375)(-1675 1325);
WIRE 16 -1 (-1825 1375)(-1675 1375);
WIRE 16 -1 (-1675 1325)(-1675 1275);
WIRE 16 -1 (-1825 1325)(-1675 1325);
WIRE 16 -1 (-1675 1275)(-1675 1225);
WIRE 16 -1 (-1825 1275)(-1675 1275);
WIRE 16 -1 (-1675 1225)(-1675 1175);
WIRE 16 -1 (-1825 1225)(-1675 1225);
WIRE 16 -1 (-1675 1175)(-1675 1125);
WIRE 16 -1 (-1825 1175)(-1675 1175);
WIRE 16 -1 (-1675 1125)(-1675 1075);
WIRE 16 -1 (-1825 1125)(-1675 1125);
WIRE 16 -1 (-1675 1075)(-1675 1025);
WIRE 16 -1 (-1825 1075)(-1675 1075);
WIRE 16 -1 (-1825 1025)(-1675 1025);
WIRE 16 -1 (-1675 1025)(-1675 975);
WIRE 16 -1 (-1675 975)(-1675 925);
WIRE 16 -1 (-1825 975)(-1675 975);
WIRE 16 -1 (-1675 925)(-1675 875);
WIRE 16 -1 (-1825 925)(-1675 925);
WIRE 16 -1 (-1675 875)(-1675 825);
WIRE 16 -1 (-1825 875)(-1675 875);
WIRE 16 -1 (-1825 825)(-1675 825);
DOT 1 (-5275 1150);
DOT 1 (-7250 4875);
DOT 1 (-7250 4825);
DOT 1 (-6900 4200);
DOT 1 (-1675 6525);
DOT 1 (-5275 6400);
DOT 1 (-4975 3175);
DOT 1 (-4975 3125);
DOT 1 (-4975 3325);
DOT 1 (-4975 3275);
DOT 1 (-4975 3225);
DOT 1 (-4975 3425);
DOT 1 (-4975 3375);
DOT 1 (-4975 3475);
DOT 1 (-4975 3525);
DOT 1 (-4975 3575);
DOT 1 (-4975 3675);
DOT 1 (-4975 3625);
DOT 1 (-4975 3725);
DOT 1 (-4975 3825);
DOT 1 (-4975 3775);
DOT 1 (-4975 3925);
DOT 1 (-4975 3875);
DOT 1 (-4975 3975);
DOT 1 (-4975 4025);
DOT 1 (-4975 4075);
DOT 1 (-4975 4175);
DOT 1 (-4975 4125);
DOT 1 (-4975 4225);
DOT 1 (-4975 4325);
DOT 1 (-4975 4275);
DOT 1 (-4975 4475);
DOT 1 (-4975 4425);
DOT 1 (-4975 4375);
DOT 1 (-4975 4525);
DOT 1 (-4975 4575);
DOT 1 (-4975 4725);
DOT 1 (-4975 4675);
DOT 1 (-4975 4625);
DOT 1 (-4975 4825);
DOT 1 (-4975 4775);
DOT 1 (-4975 4875);
DOT 1 (-4975 4925);
DOT 1 (-4975 4975);
DOT 1 (-4975 5025);
DOT 1 (-4975 5075);
DOT 1 (-4975 5125);
DOT 1 (-4975 5225);
DOT 1 (-4975 5175);
DOT 1 (-4975 5375);
DOT 1 (-4975 5325);
DOT 1 (-4975 5275);
DOT 1 (-4975 5475);
DOT 1 (-4975 5425);
DOT 1 (-4975 5525);
DOT 1 (-4975 5575);
DOT 1 (-4975 5625);
DOT 1 (-4975 5725);
DOT 1 (-4975 5675);
DOT 1 (-4975 5875);
DOT 1 (-4975 5825);
DOT 1 (-4975 5775);
DOT 1 (-4975 5925);
DOT 1 (-4975 5975);
DOT 1 (-4975 6025);
DOT 1 (-3500 3575);
DOT 1 (-3500 3525);
DOT 1 (-3500 3675);
DOT 1 (-3500 3625);
DOT 1 (-3500 3725);
DOT 1 (-3500 3775);
DOT 1 (-3500 3825);
DOT 1 (-3500 3925);
DOT 1 (-3500 3875);
DOT 1 (-3500 3975);
DOT 1 (-3500 4025);
DOT 1 (-3500 4075);
DOT 1 (-3500 4175);
DOT 1 (-3500 4125);
DOT 1 (-3500 4225);
DOT 1 (-3500 4275);
DOT 1 (-3500 4325);
DOT 1 (-3500 4375);
DOT 1 (-3500 4425);
DOT 1 (-3500 4475);
DOT 1 (-3500 4525);
DOT 1 (-3500 4575);
DOT 1 (-3500 4625);
DOT 1 (-3500 4675);
DOT 1 (-3500 4725);
DOT 1 (-3500 4775);
DOT 1 (-3500 4825);
DOT 1 (-3500 4875);
DOT 1 (-3500 4925);
DOT 1 (-3500 4975);
DOT 1 (-3500 5025);
DOT 1 (-3500 5075);
DOT 1 (-3500 5125);
DOT 1 (-3500 5175);
DOT 1 (-3500 5225);
DOT 1 (-3500 5275);
DOT 1 (-3500 5325);
DOT 1 (-3500 5375);
DOT 1 (-3500 5475);
DOT 1 (-3500 5425);
DOT 1 (-3500 5525);
DOT 1 (-3500 5575);
DOT 1 (-3500 5625);
DOT 1 (-3500 5725);
DOT 1 (-3500 5675);
DOT 1 (-3500 5775);
DOT 1 (-3500 5825);
DOT 1 (-3500 5875);
DOT 1 (-3500 5925);
DOT 1 (-3500 5975);
DOT 1 (-3500 6025);
DOT 1 (-3300 5925);
DOT 1 (-3300 5975);
DOT 1 (-5275 3000);
DOT 1 (-7250 4375);
DOT 1 (-6900 4300);
DOT 1 (-5275 5900);
DOT 1 (-5275 5850);
DOT 1 (-5275 5800);
DOT 1 (-5275 5750);
DOT 1 (-5275 4900);
DOT 1 (-5275 6150);
DOT 1 (-5275 4400);
DOT 1 (-8900 625);
DOT 1 (-8900 675);
DOT 1 (-8900 725);
DOT 1 (-8900 775);
DOT 1 (-8900 825);
DOT 1 (-8900 875);
DOT 1 (-8900 925);
DOT 1 (-8900 975);
DOT 1 (-8900 1025);
DOT 1 (-8900 1075);
DOT 1 (-8900 1125);
DOT 1 (-8900 1175);
DOT 1 (-8900 1225);
DOT 1 (-8900 1275);
DOT 1 (-8900 1325);
DOT 1 (-8900 1375);
DOT 1 (-8900 1425);
DOT 1 (-8900 1475);
DOT 1 (-8900 1525);
DOT 1 (-8900 1575);
DOT 1 (-8900 1625);
DOT 1 (-8900 1675);
DOT 1 (-8900 1725);
DOT 1 (-8900 1775);
DOT 1 (-8900 1825);
DOT 1 (-8900 1875);
DOT 1 (-8900 1925);
DOT 1 (-8900 1975);
DOT 1 (-8900 2025);
DOT 1 (-8900 2075);
DOT 1 (-8900 2125);
DOT 1 (-8900 2175);
DOT 1 (-8900 2225);
DOT 1 (-8900 2275);
DOT 1 (-8900 2325);
DOT 1 (-8900 2375);
DOT 1 (-8900 2425);
DOT 1 (-8900 2475);
DOT 1 (-8900 2525);
DOT 1 (-8900 2575);
DOT 1 (-8900 2625);
DOT 1 (-8900 2675);
DOT 1 (-8900 2725);
DOT 1 (-8900 2775);
DOT 1 (-8900 2825);
DOT 1 (-8900 2875);
DOT 1 (-8900 2925);
DOT 1 (-8900 3025);
DOT 1 (-8900 2975);
DOT 1 (-8900 3075);
DOT 1 (-8900 3125);
DOT 1 (-8900 3175);
DOT 1 (-8900 3225);
DOT 1 (-8900 3275);
DOT 1 (-8900 3325);
DOT 1 (-8900 3375);
DOT 1 (-8900 3425);
DOT 1 (-8900 3475);
DOT 1 (-8900 3525);
DOT 1 (-8900 3575);
DOT 1 (-8900 3625);
DOT 1 (-8900 3675);
DOT 1 (-8900 3725);
DOT 1 (-8900 3775);
DOT 1 (-8900 3825);
DOT 1 (-8900 3875);
DOT 1 (-8900 3925);
DOT 1 (-8900 3975);
DOT 1 (-8900 4075);
DOT 1 (-8900 4125);
DOT 1 (-8900 4175);
DOT 1 (-8900 4225);
DOT 1 (-8900 4275);
DOT 1 (-8900 4325);
DOT 1 (-8900 4475);
DOT 1 (-8900 4375);
DOT 1 (-8900 4425);
DOT 1 (-8900 4525);
DOT 1 (-8900 4575);
DOT 1 (-8900 4625);
DOT 1 (-8900 4675);
DOT 1 (-8900 4725);
DOT 1 (-8900 4775);
DOT 1 (-8900 4825);
DOT 1 (-8900 4875);
DOT 1 (-8900 4925);
DOT 1 (-8900 4975);
DOT 1 (-8900 5075);
DOT 1 (-8900 5025);
DOT 1 (-8900 5125);
DOT 1 (-8900 5175);
DOT 1 (-8900 5225);
DOT 1 (-8900 5275);
DOT 1 (-8900 5325);
DOT 1 (-8900 5375);
DOT 1 (-8900 5425);
DOT 1 (-8900 5475);
DOT 1 (-8900 5525);
DOT 1 (-8900 5575);
DOT 1 (-8900 5625);
DOT 1 (-8900 5675);
DOT 1 (-8900 5725);
DOT 1 (-8900 5825);
DOT 1 (-8900 5875);
DOT 1 (-8900 5925);
DOT 1 (-8900 5975);
DOT 1 (-8900 6025);
DOT 1 (-8900 6075);
DOT 1 (-8900 6125);
DOT 1 (-8900 6175);
DOT 1 (-8900 6225);
DOT 1 (-8900 6275);
DOT 1 (-8900 6325);
DOT 1 (-7250 575);
DOT 1 (-7250 625);
DOT 1 (-7250 675);
DOT 1 (-7250 725);
DOT 1 (-7250 775);
DOT 1 (-7250 825);
DOT 1 (-7250 875);
DOT 1 (-7250 975);
DOT 1 (-7250 925);
DOT 1 (-7250 1025);
DOT 1 (-7250 1075);
DOT 1 (-7250 1125);
DOT 1 (-7250 1175);
DOT 1 (-7250 1225);
DOT 1 (-7250 1275);
DOT 1 (-7250 1325);
DOT 1 (-7250 1375);
DOT 1 (-7250 1425);
DOT 1 (-7250 1475);
DOT 1 (-7250 1525);
DOT 1 (-7250 1625);
DOT 1 (-7250 1575);
DOT 1 (-7250 1675);
DOT 1 (-7250 1725);
DOT 1 (-7250 1775);
DOT 1 (-7250 1825);
DOT 1 (-7250 1875);
DOT 1 (-7250 1925);
DOT 1 (-7250 1975);
DOT 1 (-7250 2025);
DOT 1 (-6900 950);
DOT 1 (-6900 1000);
DOT 1 (-6900 900);
DOT 1 (-6900 750);
DOT 1 (-6900 800);
DOT 1 (-6900 850);
DOT 1 (-6900 1450);
DOT 1 (-6900 1500);
DOT 1 (-6900 1300);
DOT 1 (-6900 1350);
DOT 1 (-6900 1400);
DOT 1 (-6900 1200);
DOT 1 (-6900 1250);
DOT 1 (-6900 1050);
DOT 1 (-6900 1100);
DOT 1 (-6900 1150);
DOT 1 (-6900 1950);
DOT 1 (-6900 2000);
DOT 1 (-6900 1850);
DOT 1 (-6900 1900);
DOT 1 (-6900 1800);
DOT 1 (-6900 1700);
DOT 1 (-6900 1750);
DOT 1 (-6900 1600);
DOT 1 (-6900 1650);
DOT 1 (-6900 1550);
DOT 1 (-6900 2050);
DOT 1 (-7250 2075);
DOT 1 (-7250 2125);
DOT 1 (-7250 2175);
DOT 1 (-7250 2225);
DOT 1 (-7250 2275);
DOT 1 (-7250 2325);
DOT 1 (-7250 2375);
DOT 1 (-7250 2425);
DOT 1 (-7250 2475);
DOT 1 (-7250 2525);
DOT 1 (-7250 2575);
DOT 1 (-7250 2625);
DOT 1 (-7250 2675);
DOT 1 (-7250 2725);
DOT 1 (-7250 2775);
DOT 1 (-7250 2825);
DOT 1 (-7250 2875);
DOT 1 (-7250 2925);
DOT 1 (-7250 2975);
DOT 1 (-7250 3025);
DOT 1 (-7250 3075);
DOT 1 (-7250 3125);
DOT 1 (-7250 3175);
DOT 1 (-7250 3225);
DOT 1 (-7250 3275);
DOT 1 (-7250 3325);
DOT 1 (-7250 3425);
DOT 1 (-7250 3375);
DOT 1 (-7250 3475);
DOT 1 (-7250 3525);
DOT 1 (-7250 3575);
DOT 1 (-7250 3675);
DOT 1 (-7250 3625);
DOT 1 (-7250 3725);
DOT 1 (-7250 3775);
DOT 1 (-7250 3825);
DOT 1 (-7250 3925);
DOT 1 (-7250 3875);
DOT 1 (-7250 3975);
DOT 1 (-7250 4025);
DOT 1 (-7250 4075);
DOT 1 (-6900 2450);
DOT 1 (-6900 2500);
DOT 1 (-6900 2550);
DOT 1 (-6900 2350);
DOT 1 (-6900 2400);
DOT 1 (-6900 2200);
DOT 1 (-6900 2250);
DOT 1 (-6900 2300);
DOT 1 (-6900 2100);
DOT 1 (-6900 2150);
DOT 1 (-6900 3000);
DOT 1 (-6900 3050);
DOT 1 (-6900 2950);
DOT 1 (-6900 2850);
DOT 1 (-6900 2900);
DOT 1 (-6900 2750);
DOT 1 (-6900 2800);
DOT 1 (-6900 2700);
DOT 1 (-6900 2600);
DOT 1 (-6900 2650);
DOT 1 (-6900 3500);
DOT 1 (-6900 3550);
DOT 1 (-6900 3350);
DOT 1 (-6900 3400);
DOT 1 (-6900 3450);
DOT 1 (-6900 3250);
DOT 1 (-6900 3300);
DOT 1 (-6900 3100);
DOT 1 (-6900 3150);
DOT 1 (-6900 3200);
DOT 1 (-6900 4000);
DOT 1 (-6900 4050);
DOT 1 (-6900 3900);
DOT 1 (-6900 3950);
DOT 1 (-6900 3850);
DOT 1 (-6900 3750);
DOT 1 (-6900 3800);
DOT 1 (-6900 3650);
DOT 1 (-6900 3700);
DOT 1 (-6900 3600);
DOT 1 (-5275 350);
DOT 1 (-5275 300);
DOT 1 (-5275 400);
DOT 1 (-5275 450);
DOT 1 (-5275 500);
DOT 1 (-5275 550);
DOT 1 (-5275 600);
DOT 1 (-5275 650);
DOT 1 (-5275 700);
DOT 1 (-5275 750);
DOT 1 (-5275 800);
DOT 1 (-5275 850);
DOT 1 (-5275 900);
DOT 1 (-5275 950);
DOT 1 (-5275 1000);
DOT 1 (-5275 1050);
DOT 1 (-5275 1100);
DOT 1 (-5275 1250);
DOT 1 (-5275 1200);
DOT 1 (-5275 1300);
DOT 1 (-5275 1350);
DOT 1 (-5275 1400);
DOT 1 (-5275 1450);
DOT 1 (-5275 1500);
DOT 1 (-5275 1600);
DOT 1 (-5275 1550);
DOT 1 (-5275 1650);
DOT 1 (-5275 1750);
DOT 1 (-5275 1700);
DOT 1 (-5275 1800);
DOT 1 (-5275 1850);
DOT 1 (-5275 1900);
DOT 1 (-5275 1950);
DOT 1 (-5275 2000);
DOT 1 (-5275 2050);
DOT 1 (-5275 2100);
DOT 1 (-5275 2150);
DOT 1 (-5275 2200);
DOT 1 (-5275 2250);
DOT 1 (-5275 2300);
DOT 1 (-5275 2350);
DOT 1 (-5275 2400);
DOT 1 (-5275 2450);
DOT 1 (-5275 2500);
DOT 1 (-5275 2550);
DOT 1 (-5275 2600);
DOT 1 (-5275 2650);
DOT 1 (-5275 2700);
DOT 1 (-5275 2750);
DOT 1 (-5275 2800);
DOT 1 (-5275 2850);
DOT 1 (-5275 2900);
DOT 1 (-5275 2950);
DOT 1 (-5275 3050);
DOT 1 (-5275 3200);
DOT 1 (-5275 3150);
DOT 1 (-5275 3100);
DOT 1 (-5275 3300);
DOT 1 (-5275 3250);
DOT 1 (-5275 3350);
DOT 1 (-5275 3400);
DOT 1 (-5275 3450);
DOT 1 (-5275 3500);
DOT 1 (-5275 3550);
DOT 1 (-5275 3600);
DOT 1 (-5275 3650);
DOT 1 (-5275 3700);
DOT 1 (-5275 3800);
DOT 1 (-5275 3750);
DOT 1 (-5275 3850);
DOT 1 (-5275 3900);
DOT 1 (-5275 4050);
DOT 1 (-5275 4100);
DOT 1 (-6900 4100);
DOT 1 (-7250 4125);
DOT 1 (-7250 4175);
DOT 1 (-7250 4225);
DOT 1 (-7250 4275);
DOT 1 (-7250 4325);
DOT 1 (-7250 4425);
DOT 1 (-7250 4475);
DOT 1 (-7250 4525);
DOT 1 (-7250 4575);
DOT 1 (-7250 4625);
DOT 1 (-7250 4675);
DOT 1 (-7250 4725);
DOT 1 (-7250 4775);
DOT 1 (-7250 4925);
DOT 1 (-7250 4975);
DOT 1 (-7250 5025);
DOT 1 (-7250 5075);
DOT 1 (-7250 5125);
DOT 1 (-7250 5175);
DOT 1 (-7250 5225);
DOT 1 (-7250 5275);
DOT 1 (-7250 5325);
DOT 1 (-7250 5375);
DOT 1 (-7250 5425);
DOT 1 (-7250 5475);
DOT 1 (-7250 5525);
DOT 1 (-7250 5575);
DOT 1 (-7250 5625);
DOT 1 (-7250 5725);
DOT 1 (-7250 5675);
DOT 1 (-7250 5775);
DOT 1 (-7250 5825);
DOT 1 (-7250 5875);
DOT 1 (-7250 5975);
DOT 1 (-7250 5925);
DOT 1 (-7250 6025);
DOT 1 (-7250 6075);
DOT 1 (-7250 6125);
DOT 1 (-6900 4500);
DOT 1 (-6900 4550);
DOT 1 (-6900 4600);
DOT 1 (-6900 4400);
DOT 1 (-6900 4450);
DOT 1 (-6900 4250);
DOT 1 (-6900 4350);
DOT 1 (-6900 4150);
DOT 1 (-6900 5050);
DOT 1 (-6900 5100);
DOT 1 (-6900 5000);
DOT 1 (-6900 4900);
DOT 1 (-6900 4950);
DOT 1 (-6900 4800);
DOT 1 (-6900 4850);
DOT 1 (-6900 4750);
DOT 1 (-6900 4650);
DOT 1 (-6900 4700);
DOT 1 (-6900 5550);
DOT 1 (-6900 5600);
DOT 1 (-6900 5400);
DOT 1 (-6900 5450);
DOT 1 (-6900 5500);
DOT 1 (-6900 5300);
DOT 1 (-6900 5350);
DOT 1 (-6900 5150);
DOT 1 (-6900 5200);
DOT 1 (-6900 5250);
DOT 1 (-6900 6050);
DOT 1 (-6900 6100);
DOT 1 (-6900 5950);
DOT 1 (-6900 6000);
DOT 1 (-6900 5900);
DOT 1 (-6900 5800);
DOT 1 (-6900 5850);
DOT 1 (-6900 5650);
DOT 1 (-6900 5700);
DOT 1 (-6900 5750);
DOT 1 (-7250 6175);
DOT 1 (-7250 6225);
DOT 1 (-7250 6275);
DOT 1 (-7250 6325);
DOT 1 (-5275 4200);
DOT 1 (-5275 4250);
DOT 1 (-5275 4300);
DOT 1 (-5275 4350);
DOT 1 (-5275 4450);
DOT 1 (-5275 4500);
DOT 1 (-5275 4550);
DOT 1 (-5275 4600);
DOT 1 (-5275 4650);
DOT 1 (-5275 4700);
DOT 1 (-5275 4800);
DOT 1 (-5275 4750);
DOT 1 (-5275 4850);
DOT 1 (-5275 4950);
DOT 1 (-5275 5000);
DOT 1 (-5275 5050);
DOT 1 (-5275 5100);
DOT 1 (-5275 5200);
DOT 1 (-5275 5150);
DOT 1 (-5275 5250);
DOT 1 (-5275 5300);
DOT 1 (-5275 5350);
DOT 1 (-5275 5400);
DOT 1 (-5275 5450);
DOT 1 (-5275 5500);
DOT 1 (-5275 5550);
DOT 1 (-5275 5600);
DOT 1 (-5275 5650);
DOT 1 (-5275 5700);
DOT 1 (-5275 5950);
DOT 1 (-5275 6000);
DOT 1 (-5275 6050);
DOT 1 (-5275 6100);
DOT 1 (-5275 6200);
DOT 1 (-5275 6250);
DOT 1 (-5275 6350);
DOT 1 (-3475 925);
DOT 1 (-3475 1525);
DOT 1 (-3475 1575);
DOT 1 (-3475 1625);
DOT 1 (-3475 1775);
DOT 1 (-3475 1875);
DOT 1 (-3475 1825);
DOT 1 (-3475 1925);
DOT 1 (-3475 1975);
DOT 1 (-3475 2025);
DOT 1 (-3475 2075);
DOT 1 (-3475 2125);
DOT 1 (-3475 2175);
DOT 1 (-3475 2275);
DOT 1 (-3475 2225);
DOT 1 (-3475 2325);
DOT 1 (-3475 2375);
DOT 1 (-3475 2425);
DOT 1 (-3475 2475);
DOT 1 (-3475 2525);
DOT 1 (-3300 2825);
DOT 1 (-3300 2875);
DOT 1 (-3300 2925);
DOT 1 (-3300 3025);
DOT 1 (-3300 2975);
DOT 1 (-3300 3075);
DOT 1 (-3300 3125);
DOT 1 (-3300 3175);
DOT 1 (-3300 3225);
DOT 1 (-3300 3275);
DOT 1 (-3300 3325);
DOT 1 (-3300 3375);
DOT 1 (-3300 3425);
DOT 1 (-3300 3475);
DOT 1 (-3300 3525);
DOT 1 (-3300 3575);
DOT 1 (-3300 3675);
DOT 1 (-3300 3625);
DOT 1 (-3300 3725);
DOT 1 (-3300 3775);
DOT 1 (-3300 3825);
DOT 1 (-3300 3875);
DOT 1 (-3300 3925);
DOT 1 (-3300 3975);
DOT 1 (-3300 4025);
DOT 1 (-3300 4075);
DOT 1 (-1675 875);
DOT 1 (-1675 925);
DOT 1 (-1675 975);
DOT 1 (-1675 1025);
DOT 1 (-1675 1075);
DOT 1 (-1675 1125);
DOT 1 (-1675 1175);
DOT 1 (-1675 1225);
DOT 1 (-1675 1275);
DOT 1 (-1675 1375);
DOT 1 (-1675 1325);
DOT 1 (-1675 1425);
DOT 1 (-1675 1475);
DOT 1 (-1675 1525);
DOT 1 (-1675 1625);
DOT 1 (-1675 1575);
DOT 1 (-1675 1675);
DOT 1 (-1675 1775);
DOT 1 (-1675 1725);
DOT 1 (-1675 1875);
DOT 1 (-1675 1825);
DOT 1 (-1675 1925);
DOT 1 (-1675 1975);
DOT 1 (-1675 2025);
DOT 1 (-1675 2175);
DOT 1 (-1675 2125);
DOT 1 (-1675 2075);
DOT 1 (-1675 2225);
DOT 1 (-1675 2275);
DOT 1 (-1675 2375);
DOT 1 (-1675 2425);
DOT 1 (-1675 2325);
DOT 1 (-1675 2475);
DOT 1 (-1675 2525);
DOT 1 (-1675 2675);
DOT 1 (-1675 2625);
DOT 1 (-1675 2575);
DOT 1 (-1675 2725);
DOT 1 (-1675 2775);
DOT 1 (-1675 2825);
DOT 1 (-1675 2925);
DOT 1 (-1675 2875);
DOT 1 (-1675 2975);
DOT 1 (-1675 3025);
DOT 1 (-1675 3075);
DOT 1 (-1675 3125);
DOT 1 (-1675 3175);
DOT 1 (-1675 3225);
DOT 1 (-1675 3325);
DOT 1 (-1675 3275);
DOT 1 (-1675 3425);
DOT 1 (-1675 3375);
DOT 1 (-1675 3475);
DOT 1 (-1675 3525);
DOT 1 (-1675 3575);
DOT 1 (-1675 3625);
DOT 1 (-1675 3675);
DOT 1 (-1675 3725);
DOT 1 (-1675 3775);
DOT 1 (-1675 3825);
DOT 1 (-1675 3925);
DOT 1 (-1675 3875);
DOT 1 (-1675 3975);
DOT 1 (-1675 4025);
DOT 1 (-1675 4075);
DOT 1 (-3300 4125);
DOT 1 (-3300 4175);
DOT 1 (-3300 4225);
DOT 1 (-3300 4275);
DOT 1 (-3300 4325);
DOT 1 (-3300 4375);
DOT 1 (-3300 4425);
DOT 1 (-3300 4475);
DOT 1 (-3300 4525);
DOT 1 (-3300 4575);
DOT 1 (-3300 4625);
DOT 1 (-3300 4675);
DOT 1 (-3300 4725);
DOT 1 (-3300 4825);
DOT 1 (-3300 4775);
DOT 1 (-3300 4875);
DOT 1 (-3300 4925);
DOT 1 (-3300 4975);
DOT 1 (-3300 5025);
DOT 1 (-3300 5075);
DOT 1 (-3300 5125);
DOT 1 (-3300 5175);
DOT 1 (-3300 5225);
DOT 1 (-3300 5275);
DOT 1 (-3300 5325);
DOT 1 (-3300 5375);
DOT 1 (-3300 5475);
DOT 1 (-3300 5425);
DOT 1 (-3300 5525);
DOT 1 (-3300 5575);
DOT 1 (-3300 5625);
DOT 1 (-3300 5725);
DOT 1 (-3300 5675);
DOT 1 (-3300 5775);
DOT 1 (-3300 5825);
DOT 1 (-3300 5875);
DOT 1 (-3300 6025);
DOT 1 (-3300 6075);
DOT 1 (-3300 6125);
DOT 1 (-3300 6175);
DOT 1 (-3300 6225);
DOT 1 (-3300 6275);
DOT 1 (-3300 6325);
DOT 1 (-3300 6375);
DOT 1 (-3300 6425);
DOT 1 (-3300 6475);
DOT 1 (-3300 6525);
DOT 1 (-1675 4125);
DOT 1 (-1675 4175);
DOT 1 (-1675 4225);
DOT 1 (-1675 4275);
DOT 1 (-1675 4325);
DOT 1 (-1675 4425);
DOT 1 (-1675 4475);
DOT 1 (-1675 4375);
DOT 1 (-1675 4525);
DOT 1 (-1675 4575);
DOT 1 (-1675 4725);
DOT 1 (-1675 4675);
DOT 1 (-1675 4625);
DOT 1 (-1675 4775);
DOT 1 (-1675 4825);
DOT 1 (-1675 4875);
DOT 1 (-1675 4975);
DOT 1 (-1675 4925);
DOT 1 (-1675 5025);
DOT 1 (-1675 5075);
DOT 1 (-1675 5125);
DOT 1 (-1675 5175);
DOT 1 (-1675 5225);
DOT 1 (-1675 5275);
DOT 1 (-1675 5375);
DOT 1 (-1675 5325);
DOT 1 (-1675 5475);
DOT 1 (-1675 5425);
DOT 1 (-1675 5525);
DOT 1 (-1675 5575);
DOT 1 (-1675 5625);
DOT 1 (-1675 5725);
DOT 1 (-1675 5675);
DOT 1 (-1675 5775);
DOT 1 (-1675 5825);
DOT 1 (-1675 5875);
DOT 1 (-1675 5975);
DOT 1 (-1675 5925);
DOT 1 (-1675 6025);
DOT 1 (-1675 6075);
DOT 1 (-1675 6125);
DOT 1 (-1675 6225);
DOT 1 (-1675 6175);
DOT 1 (-1675 6275);
DOT 1 (-1675 6375);
DOT 1 (-1675 6325);
DOT 1 (-1675 6425);
DOT 1 (-1675 6475);
DOT 1 (-8900 5775);
DOT 1 (-5275 6300);
DOT 1 (-5275 4000);
DOT 1 (-5275 3950);
DOT 1 (-5275 4150);
DOT 1 (-8900 4025);
DOT 1 (-3300 2775);
DOT 1 (-3475 2625);
DOT 1 (-3475 1725);
DOT 1 (-3475 1675);
QUIT
